G04 ================== begin FILE IDENTIFICATION RECORD ==================*
G04 Layout Name:  9127_F0T_Expander_BD_F_v02_0110_1240.brd*
G04 Film Name:    pmb*
G04 File Format:  Gerber RS274X*
G04 File Origin:  Cadence Allegro 17.2-S081*
G04 Origin Date:  Wed Jan 11 16:06:13 2023*
G04 *
G04 Layer:  DRAWING FORMAT/TITLE_BLOCK_A*
G04 Layer:  VIA CLASS/PASTEMASK_BOTTOM*
G04 Layer:  PACKAGE GEOMETRY/PASTEMASK_BOTTOM*
G04 Layer:  DRAWING FORMAT/TITLE_BLOCK*
G04 Layer:  PIN/PASTEMASK_BOTTOM*
G04 Layer:  MANUFACTURING/PHOTOPLOT_OUTLINE*
G04 Layer:  DRAWING FORMAT/TITLE_DATA_PMB*
G04 *
G04 Offset:    (0.00 0.00)*
G04 Mirror:    No*
G04 Mode:      Positive*
G04 Rotation:  0*
G04 FullContactRelief:  No*
G04 UndefLineWidth:     6.00*
G04 ================== end FILE IDENTIFICATION RECORD ====================*
%FSLAX25Y25*MOIN*%
%IR0*IPPOS*OFA0.00000B0.00000*MIA0B0*SFA1.00000B1.00000*%
%ADD33O,.137X.062*%
%ADD20C,.02*%
%ADD52R,.111X.095*%
%ADD38R,.0041X.016*%
%ADD43R,.016X.0041*%
%ADD27O,.137X.064*%
%ADD22C,.04*%
%ADD67C,.061*%
%ADD11C,.026*%
%ADD59C,.028*%
%ADD32C,.064*%
%ADD60C,.048*%
%ADD68R,.061X.061*%
%AMMACRO24*
4,1,28,-.00748,.00052,
-.00984,.00052,
-.00984,.00603,
-.009782,.006705,
-.009607,.007359,
-.009321,.007974,
-.008933,.008529,
-.008455,.009009,
-.0079,.009398,
-.007286,.009685,
-.006632,.009861,
-.005957,.00992,
-.00591,.00992,
.00591,.00992,
.006585,.009869,
.007242,.009701,
.007859,.009421,
.008418,.009039,
.008903,.008565,
.009297,.008015,
.009591,.007404,
.009773,.006751,
.00984,.006077,
.00984,.00603,
.00984,.00052,
.00748,.00052,
.00748,-.00991,
-.00748,-.00991,
-.00748,.00052,
0.0*
%
%ADD24MACRO24*%
%AMMACRO30*
4,1,28,.00052,.00748,
.00052,.00984,
.00603,.00984,
.006705,.009782,
.007359,.009607,
.007974,.009321,
.008529,.008933,
.009009,.008455,
.009398,.0079,
.009685,.007286,
.009861,.006632,
.00992,.005957,
.00992,.00591,
.00992,-.00591,
.009869,-.006585,
.009701,-.007242,
.009421,-.007859,
.009039,-.008418,
.008565,-.008903,
.008015,-.009297,
.007404,-.009591,
.006751,-.009773,
.006077,-.00984,
.00603,-.00984,
.00052,-.00984,
.00052,-.00748,
-.00991,-.00748,
-.00991,.00748,
.00052,.00748,
0.0*
%
%ADD30MACRO30*%
%AMMACRO64*
4,1,8,.0034,.0082,
-.0034,.0082,
-.0082,.0034,
-.0082,-.00341,
-.00341,-.0082,
.0034,-.0082,
.0082,-.0034,
.0082,.0034,
.0034,.0082,
0.0*
%
%ADD64MACRO64*%
%AMMACRO65*
4,1,8,.0082,-.0034,
.0082,.0034,
.0034,.0082,
-.00341,.0082,
-.0082,.00341,
-.0082,-.0034,
-.0034,-.0082,
.0034,-.0082,
.0082,-.0034,
0.0*
%
%ADD65MACRO65*%
%AMMACRO23*
4,1,28,-.00748,-.00051,
-.00984,-.00051,
-.00984,-.00602,
-.009782,-.006695,
-.009607,-.007349,
-.009321,-.007964,
-.008933,-.008519,
-.008455,-.008998,
-.0079,-.009388,
-.007287,-.009675,
-.006632,-.009851,
-.005958,-.00991,
-.00591,-.00991,
.00591,-.00991,
.006585,-.009859,
.007242,-.009691,
.007859,-.009411,
.008418,-.009029,
.008903,-.008555,
.009297,-.008005,
.00959,-.007394,
.009773,-.006742,
.00984,-.006068,
.00984,-.00602,
.00984,-.00051,
.00748,-.00051,
.00748,.00992,
-.00748,.00992,
-.00748,-.00051,
0.0*
%
%ADD23MACRO23*%
%AMMACRO29*
4,1,28,-.00051,.00748,
-.00051,.00984,
-.00602,.00984,
-.006695,.009782,
-.007349,.009607,
-.007964,.009321,
-.008519,.008933,
-.008998,.008455,
-.009388,.0079,
-.009675,.007287,
-.009851,.006632,
-.00991,.005958,
-.00991,.00591,
-.00991,-.00591,
-.009859,-.006585,
-.009691,-.007242,
-.009411,-.007859,
-.009029,-.008418,
-.008555,-.008903,
-.008005,-.009297,
-.007394,-.00959,
-.006742,-.009773,
-.006068,-.00984,
-.00602,-.00984,
-.00051,-.00984,
-.00051,-.00748,
.00992,-.00748,
.00992,.00748,
-.00051,.00748,
0.0*
%
%ADD29MACRO29*%
%ADD53R,.02X.01*%
%ADD62R,.02X.011*%
%ADD44R,.02X.02*%
%ADD13R,.01X.02*%
%ADD49R,.022X.01*%
%ADD37R,.02X.02*%
%ADD61R,.021X.012*%
%ADD51R,.01X.022*%
%ADD70R,.022X.04*%
%ADD58R,.01X.061*%
%ADD34R,.015X.012*%
%ADD28R,.05X.04*%
%ADD21R,.012X.015*%
%ADD16R,.04X.05*%
%ADD74R,.032X.024*%
%ADD40R,.053X.022*%
%ADD39R,.034X.014*%
%AMMACRO35*
21,1,.016,.0041,0.0,0.0,135.*%
%ADD35MACRO35*%
%ADD71R,.014X.052*%
%ADD56R,.044X.014*%
%ADD36R,.024X.016*%
%ADD31R,.014X.061*%
%ADD75O,.044X.071*%
%ADD69R,.036X.032*%
%ADD57R,.014X.044*%
%ADD55R,.044X.024*%
%ADD45R,.016X.024*%
%ADD41R,.024X.017*%
%ADD15R,.032X.028*%
%ADD42R,.028X.032*%
%ADD72R,.024X.046*%
%AMMACRO46*
21,1,.016,.0041,0.0,0.0,123.215*%
%ADD46MACRO46*%
%ADD17R,.054X.044*%
%ADD48R,.071X.046*%
%ADD47R,.044X.054*%
%ADD73R,.017X.046*%
%ADD12R,.046X.071*%
%ADD76O,.044X.087*%
%ADD10C,.256*%
%ADD50R,.124X.124*%
%ADD54R,.079X.059*%
%AMMACRO26*
4,1,28,-.00052,-.00748,
-.00052,-.00984,
-.00603,-.00984,
-.006705,-.009782,
-.007359,-.009607,
-.007974,-.009321,
-.008529,-.008933,
-.009009,-.008455,
-.009398,-.0079,
-.009685,-.007286,
-.009861,-.006632,
-.00992,-.005957,
-.00992,-.00591,
-.00992,.00591,
-.009869,.006585,
-.009701,.007242,
-.009421,.007859,
-.009039,.008418,
-.008565,.008903,
-.008015,.009297,
-.007404,.009591,
-.006751,.009773,
-.006077,.00984,
-.00603,.00984,
-.00052,.00984,
-.00052,.00748,
.00991,.00748,
.00991,-.00748,
-.00052,-.00748,
0.0*
%
%ADD26MACRO26*%
%AMMACRO18*
4,1,28,.00748,-.00052,
.00984,-.00052,
.00984,-.00603,
.009782,-.006705,
.009607,-.007359,
.009321,-.007974,
.008933,-.008529,
.008455,-.009009,
.0079,-.009398,
.007286,-.009685,
.006632,-.009861,
.005957,-.00992,
.00591,-.00992,
-.00591,-.00992,
-.006585,-.009869,
-.007242,-.009701,
-.007859,-.009421,
-.008418,-.009039,
-.008903,-.008565,
-.009297,-.008015,
-.009591,-.007404,
-.009773,-.006751,
-.00984,-.006077,
-.00984,-.00603,
-.00984,-.00052,
-.00748,-.00052,
-.00748,.00991,
.00748,.00991,
.00748,-.00052,
0.0*
%
%ADD18MACRO18*%
%ADD14R,.059X.079*%
%AMMACRO66*
4,1,8,-.0034,-.0082,
.0034,-.0082,
.0082,-.0034,
.0082,.00341,
.00341,.0082,
-.0034,.0082,
-.0082,.0034,
-.0082,-.0034,
-.0034,-.0082,
0.0*
%
%ADD66MACRO66*%
%AMMACRO63*
4,1,8,-.0082,.0034,
-.0082,-.0034,
-.0034,-.0082,
.00341,-.0082,
.0082,-.00341,
.0082,.0034,
.0034,.0082,
-.0034,.0082,
-.0082,.0034,
0.0*
%
%ADD63MACRO63*%
%AMMACRO25*
4,1,28,.00051,-.00748,
.00051,-.00984,
.00602,-.00984,
.006695,-.009782,
.007349,-.009607,
.007964,-.009321,
.008519,-.008933,
.008998,-.008455,
.009388,-.0079,
.009675,-.007287,
.009851,-.006632,
.00991,-.005958,
.00991,-.00591,
.00991,.00591,
.009859,.006585,
.009691,.007242,
.009411,.007859,
.009029,.008418,
.008555,.008903,
.008005,.009297,
.007394,.00959,
.006742,.009773,
.006068,.00984,
.00602,.00984,
.00051,.00984,
.00051,.00748,
-.00992,.00748,
-.00992,-.00748,
.00051,-.00748,
0.0*
%
%ADD25MACRO25*%
%AMMACRO19*
4,1,28,.00748,.00051,
.00984,.00051,
.00984,.00602,
.009782,.006695,
.009607,.007349,
.009321,.007964,
.008933,.008519,
.008455,.008998,
.0079,.009388,
.007287,.009675,
.006632,.009851,
.005958,.00991,
.00591,.00991,
-.00591,.00991,
-.006585,.009859,
-.007242,.009691,
-.007859,.009411,
-.008418,.009029,
-.008903,.008555,
-.009297,.008005,
-.00959,.007394,
-.009773,.006742,
-.00984,.006068,
-.00984,.00602,
-.00984,.00051,
-.00748,.00051,
-.00748,-.00992,
.00748,-.00992,
.00748,.00051,
0.0*
%
%ADD19MACRO19*%
%ADD77C,.006*%
G75*
%LPD*%
G75*
G54D10*
X13780Y1226024D03*
X79331Y1186654D03*
X390354Y1141024D03*
X536418Y1086654D03*
X854291Y1225118D03*
X993504Y1170748D03*
X1304528Y1141024D03*
X1450591Y1086654D03*
X1761614Y1215000D03*
X1827165Y1235630D03*
G54D11*
X11011Y79720D03*
X10292Y94236D03*
X12786Y87903D03*
X10131Y115473D03*
X19855Y133000D03*
X15948Y141267D03*
X16909Y153263D03*
X12247Y166341D03*
X17313Y166937D03*
X21909Y153263D03*
X22335Y166721D03*
X18320Y195176D03*
X15139Y201683D03*
X22599Y228646D03*
X18206Y244571D03*
X15586Y249108D03*
X18206Y264571D03*
X8335Y280663D03*
X14807Y282181D03*
X15586Y269108D03*
X15499Y288542D03*
X14197Y1014205D03*
X20346Y1069466D03*
X21200Y1091800D03*
X12599Y1438143D03*
X16304Y1468196D03*
X15889Y1494254D03*
X10089D03*
X26588Y97667D03*
X35442D03*
X35048Y103411D03*
X26565Y177448D03*
X32507Y180517D03*
X32585Y199248D03*
X27340Y230556D03*
X36185Y230117D03*
X31595Y227824D03*
X25549Y256394D03*
X29116Y281129D03*
X37117Y279991D03*
X25549Y276394D03*
X34359Y541135D03*
X34732Y534909D03*
X34425Y546553D03*
X34448Y552726D03*
X36494Y616905D03*
X36306Y622285D03*
X27686Y625311D03*
X36692Y633724D03*
X36575Y627713D03*
X28818Y682139D03*
X30479Y1006509D03*
X36024Y1069703D03*
X31631Y1198651D03*
X29880Y1441702D03*
X25674Y1486291D03*
X45988Y90512D03*
X51026Y242913D03*
X48596Y451419D03*
X49643Y464419D03*
X41643Y464919D03*
X43948Y492108D03*
X44563Y482165D03*
X43804Y500202D03*
X45256Y495993D03*
X40362Y610548D03*
X54192Y633473D03*
X42172Y633716D03*
X49192Y628078D03*
X47179Y633736D03*
X42192Y641817D03*
X47949Y822718D03*
X53549Y843118D03*
X52077Y905295D03*
X42470Y1006738D03*
X47314Y1072228D03*
X41172Y1079064D03*
X55188Y1205179D03*
X51023Y1201416D03*
X48842Y1211109D03*
X53479Y1216256D03*
X39452Y1250932D03*
X64829Y92874D03*
X55871Y99961D03*
X70656Y117775D03*
X69607Y135361D03*
X66780Y169454D03*
X59280D03*
X65189Y223661D03*
X65737Y445603D03*
X57857Y446071D03*
X67670Y464818D03*
X58224Y465004D03*
X63154Y462371D03*
X61330Y544895D03*
X63859Y590801D03*
X63684Y597130D03*
X67684Y605637D03*
X66510Y628242D03*
X58181Y627908D03*
X68598Y859415D03*
X59104Y880162D03*
X63969Y869475D03*
X63930Y874694D03*
X63745Y887763D03*
X71528Y913190D03*
X59962Y910251D03*
X55699Y1072761D03*
X61588Y1074481D03*
X62109Y1084656D03*
Y1079656D03*
Y1091656D03*
X60269Y1198820D03*
X63094Y1207604D03*
X55596Y1210466D03*
X65478Y1541980D03*
X64747Y1555890D03*
X69816Y1592527D03*
X60554Y1612002D03*
X66291Y1633801D03*
X82661Y143740D03*
X80041Y148277D03*
X83272Y157842D03*
X80502Y177616D03*
X81083Y172190D03*
X74939Y188727D03*
X72061Y208695D03*
X71696Y226141D03*
X75438Y265701D03*
X85541Y266114D03*
X80525Y265896D03*
X83014Y281982D03*
X77073Y281716D03*
X83819Y290755D03*
X85812Y558161D03*
X78133Y566597D03*
X87243Y564892D03*
X78733Y578405D03*
X84159Y578986D03*
X83684Y596729D03*
X72515Y596089D03*
X77734Y596782D03*
X78129Y656900D03*
X82648Y670679D03*
X73914Y660107D03*
X84845Y659857D03*
X82562Y680037D03*
X78735Y683426D03*
X74700Y842890D03*
X86061Y874859D03*
X80593Y946082D03*
X87632Y1007522D03*
X87000Y1597855D03*
X74909Y1593009D03*
X71910Y1625009D03*
X78291Y1625743D03*
X83689Y1624736D03*
X91224Y141247D03*
X95711Y143518D03*
X94811Y152373D03*
X103456Y157370D03*
X98826Y172665D03*
X98763Y178560D03*
X98653Y183834D03*
X98943Y200864D03*
X92898Y192490D03*
X98173Y190185D03*
X98966Y207037D03*
X99032Y212455D03*
X88098Y231021D03*
X103841Y228631D03*
X89900Y281307D03*
X95943Y377953D03*
X88875Y840940D03*
X90000Y871389D03*
X103770Y868206D03*
X91278Y892822D03*
X96395Y905405D03*
X103692Y900295D03*
X91387Y905295D03*
X103836Y988813D03*
X95836D03*
X94398Y1006648D03*
X91765Y1018307D03*
X88007Y1013678D03*
X88479Y1023731D03*
X100594Y1035088D03*
X103124Y1165091D03*
X119582Y102249D03*
X118307Y110784D03*
X113307D03*
X117886Y124663D03*
X112864Y124879D03*
X107798Y124283D03*
X119230Y138838D03*
X107540Y192665D03*
X117501Y201683D03*
X107572Y208864D03*
X117948Y249108D03*
X117539Y547918D03*
X120250Y758841D03*
X109591Y796905D03*
X110887Y884000D03*
X111836Y988813D03*
X119836D03*
X110409Y1024094D03*
X108971Y1109564D03*
Y1147364D03*
X109415Y1202103D03*
X118533Y1207737D03*
X112048Y1214372D03*
X107803Y1218169D03*
X128950Y97667D03*
X122867Y125107D03*
X131481Y143762D03*
X125381Y148717D03*
X120682Y195176D03*
X134947Y199248D03*
X129702Y230556D03*
X133957Y227824D03*
X120568Y244571D03*
X127911Y256394D03*
X126131Y359511D03*
X125753Y365856D03*
X122437Y860775D03*
X123387Y892000D03*
X135836Y988813D03*
X127836D03*
X124079Y1021954D03*
X120617Y1029427D03*
X124925Y1102091D03*
X130380Y1105091D03*
X124925Y1114691D03*
Y1127291D03*
X130380Y1117691D03*
X124925Y1139891D03*
X130380Y1130291D03*
X130434Y1144964D03*
X130380Y1155491D03*
X124925Y1152491D03*
X130434Y1170164D03*
X124925Y1165091D03*
Y1177691D03*
X131000Y1180266D03*
X136104Y1214835D03*
X135757Y1221407D03*
X135448Y1229402D03*
Y1234921D03*
X126433Y1230407D03*
X137410Y103411D03*
X137804Y97667D03*
X148600Y90650D03*
X138547Y230117D03*
X148061Y378600D03*
X140431Y546805D03*
X147925Y615600D03*
X149469Y634190D03*
X152658Y645389D03*
X136862Y857244D03*
X151836Y988813D03*
X143836D03*
X142026Y1012354D03*
X136571Y1009354D03*
Y1021954D03*
X142026Y1024954D03*
X144640Y1039439D03*
X150952Y1040115D03*
X139862Y1224472D03*
X167191Y92874D03*
X153912Y90615D03*
X161642Y169454D03*
X167551Y223661D03*
X164496Y309405D03*
X161715Y546062D03*
X159836Y988813D03*
X155836Y997860D03*
X153693Y1051037D03*
X156299Y1143390D03*
X165649Y1159350D03*
Y1151870D03*
X167507Y1146271D03*
X168986Y1170092D03*
X167519Y1164960D03*
X170278Y120467D03*
X185023Y143740D03*
X182403Y148277D03*
X171402Y156497D03*
X169142Y169454D03*
X182864Y177616D03*
X183445Y172190D03*
X177301Y188727D03*
X174423Y208695D03*
X174058Y226141D03*
X177800Y265701D03*
X182887Y265896D03*
X179435Y281716D03*
X178689Y1135036D03*
X169389Y1155610D03*
X182478Y1194917D03*
X193007Y100625D03*
X186026Y97475D03*
X193586Y141247D03*
X198073Y143518D03*
X197173Y152373D03*
X201015Y183834D03*
X201125Y178560D03*
X201188Y172665D03*
X195260Y192490D03*
X200535Y190185D03*
X201305Y200864D03*
X201394Y212455D03*
X201328Y207037D03*
X187903Y266114D03*
X192262Y281307D03*
X185376Y281982D03*
X186181Y290755D03*
X185328Y545528D03*
X198940Y551040D03*
X186184Y1135040D03*
X193700Y1217322D03*
X205848Y60513D03*
X214389Y86012D03*
X210482Y94279D03*
X215669Y110784D03*
X210160Y124283D03*
X215226Y124879D03*
X209902Y196665D03*
X209934Y208864D03*
X214983Y218085D03*
X206203Y228631D03*
X204675Y382109D03*
X215500Y544000D03*
X204674Y551683D03*
X208500Y595500D03*
X203500Y606929D03*
X208000Y604567D03*
X203460Y618400D03*
X203741Y612592D03*
X209158Y610072D03*
X209094Y616317D03*
X212401Y1209842D03*
X216141Y1213582D03*
X204921Y1217322D03*
X212401D03*
X221944Y102249D03*
X231312Y97667D03*
X220669Y110784D03*
X225229Y125107D03*
X220248Y124663D03*
X227743Y148717D03*
X221592Y138838D03*
X223044Y195176D03*
X219863Y201683D03*
X232064Y230556D03*
X227323Y228646D03*
X220310Y249108D03*
X222930Y244571D03*
X233417Y253198D03*
X233258Y359186D03*
X228267Y404718D03*
Y412718D03*
X223500Y568000D03*
X221693Y594982D03*
X220333Y617930D03*
X218458Y608776D03*
X225825Y635684D03*
X232998Y1058763D03*
X230321Y1050045D03*
X224169Y1055975D03*
X225001Y1062847D03*
X224780Y1478149D03*
X217985Y1483055D03*
X225765Y1471985D03*
X233313Y1476699D03*
X221899Y1488800D03*
X218021Y1494724D03*
X222843Y1498442D03*
X233180Y1486442D03*
X233166Y1491454D03*
X226135Y1502442D03*
X230758Y1505046D03*
X226971Y1514578D03*
X227552Y1530675D03*
X232622Y1531104D03*
X226971Y1522578D03*
X219981Y1530797D03*
X223322Y1518578D03*
X222119Y1539941D03*
X227882Y1540816D03*
X233753Y1539752D03*
X239772Y103411D03*
X240166Y97667D03*
X237309Y199248D03*
X240909Y230117D03*
X236319Y227824D03*
X234986Y336161D03*
X236264Y342494D03*
X242396Y499906D03*
X245362Y546712D03*
X246695Y626359D03*
X250102Y656321D03*
X235790Y754332D03*
X248556Y824003D03*
X246311Y819000D03*
X238400Y836900D03*
X250165Y1055787D03*
X240597Y1053324D03*
X234976Y1481676D03*
X243535Y1511473D03*
X245500Y1517033D03*
X237633Y1511909D03*
X244600Y1531700D03*
X240808Y1519942D03*
X235687Y1522578D03*
X237580Y1528604D03*
X245937Y1524237D03*
X239949Y1541327D03*
X244912Y1539389D03*
X250962Y90650D03*
X256274Y90615D03*
X260595Y99961D03*
X264004Y169454D03*
X265011Y403307D03*
X260111Y443585D03*
X252695Y442956D03*
X257999Y433003D03*
X261965Y458455D03*
X262526Y451108D03*
X252542Y507084D03*
X252688Y636364D03*
X256303Y812254D03*
X255289Y824340D03*
X252305Y831018D03*
X265733Y1064608D03*
X250876Y1532782D03*
X255909Y1542043D03*
X250790Y1539759D03*
X275615Y75385D03*
X269553Y92874D03*
X274613Y132920D03*
X271504Y169454D03*
X279663Y188727D03*
X276785Y208695D03*
X276420Y226141D03*
X269913Y223661D03*
X280162Y265701D03*
X281797Y281716D03*
X277575Y395084D03*
X278784Y435158D03*
X278529Y440489D03*
X282230Y458572D03*
X275123Y847874D03*
X279945Y859855D03*
X275400Y894200D03*
X281800Y929400D03*
X290113Y23188D03*
X289631Y28281D03*
X295369Y100625D03*
X288388Y97475D03*
X287385Y143740D03*
X284765Y148277D03*
X285807Y172190D03*
X285226Y177616D03*
X297622Y192490D03*
X290265Y266114D03*
X285249Y265896D03*
X294624Y281307D03*
X287738Y281982D03*
X288543Y290755D03*
X297719Y339559D03*
X291396Y350223D03*
X288500Y388000D03*
X292358Y393858D03*
X298000Y391496D03*
X295699Y382047D03*
X296000Y403500D03*
X298000Y409000D03*
X294000Y398583D03*
X286100Y1128100D03*
X290944Y1142519D03*
X287204Y1149999D03*
X296450Y1178467D03*
X296012Y1185514D03*
X307916Y60529D03*
X312844Y94279D03*
X312522Y124283D03*
X300435Y143518D03*
X299535Y152373D03*
X303377Y183834D03*
X303550Y172665D03*
X303487Y178560D03*
X302897Y190185D03*
X303667Y200864D03*
X312296Y208864D03*
X303756Y212455D03*
X303690Y207037D03*
X308565Y228631D03*
X315079Y314890D03*
X312263Y324518D03*
X299000Y377912D03*
Y386500D03*
X299088Y397912D03*
X309645Y1142519D03*
X308588Y1263349D03*
X322847Y19806D03*
X321840Y14408D03*
X322113Y26187D03*
X316751Y86012D03*
X324306Y102249D03*
X318031Y110784D03*
X323031D03*
X327591Y125107D03*
X322610Y124663D03*
X317588Y124879D03*
X330105Y148717D03*
X323954Y138838D03*
X325406Y195176D03*
X322225Y201683D03*
X329685Y228646D03*
X322672Y249108D03*
X325292Y244571D03*
X318508Y324322D03*
X315944Y332584D03*
X316067Y347937D03*
X321416Y348015D03*
X318500Y356519D03*
X327456Y550065D03*
X331240Y1221062D03*
X331015Y1232283D03*
X320624Y1284448D03*
X325683Y1287953D03*
X333674Y97667D03*
X342134Y103411D03*
X342528Y97667D03*
X336205Y143762D03*
X339671Y199248D03*
X343271Y230117D03*
X338681Y227824D03*
X334426Y230556D03*
X340988Y244297D03*
X332635Y256394D03*
X347058Y399918D03*
X346645Y418996D03*
X346390Y431730D03*
X344500Y746300D03*
X333985Y1017945D03*
X341077Y1018056D03*
X340500Y1147500D03*
X335190Y1173065D03*
X342009Y1176100D03*
X339776Y1187962D03*
X344657Y1195059D03*
X333500Y1202200D03*
X344064Y1203115D03*
X345307Y1221197D03*
X334899Y1224512D03*
X343175Y1237535D03*
X337884Y1233951D03*
X358636Y90615D03*
X353324Y90650D03*
X362957Y99961D03*
X359486Y385123D03*
X349311Y385644D03*
X354486Y385123D03*
X353894Y406060D03*
X353320Y454214D03*
X353663Y449045D03*
X353367Y459330D03*
X358754Y462060D03*
X363100Y750000D03*
X358696Y775504D03*
X358207Y836462D03*
X352545Y1142666D03*
X360877Y1157404D03*
X354420Y1157544D03*
X352931Y1167768D03*
X357950D03*
X357083Y1185205D03*
X361792Y1187310D03*
X348432Y1187215D03*
X348125Y1180175D03*
X359197Y1197626D03*
X360659Y1209789D03*
X362332Y1230265D03*
X355318Y1228760D03*
X359287Y1633665D03*
X353242Y1634202D03*
X379613Y75385D03*
X371915Y92874D03*
X373866Y169454D03*
X366366D03*
X379147Y208695D03*
X372275Y223661D03*
X378782Y226141D03*
X373264Y379429D03*
X378875Y379088D03*
X370486Y373903D03*
X366486Y385123D03*
X370160Y391569D03*
X368587Y409016D03*
X378927Y406739D03*
X367564Y456034D03*
Y461034D03*
X373703Y782555D03*
X365691Y815127D03*
X371507Y815303D03*
X370214Y943812D03*
X379928Y949774D03*
X379245Y956643D03*
X378875Y961862D03*
X378928Y967812D03*
X366429Y1185238D03*
X366222Y1180235D03*
X387948Y27288D03*
X390750Y97475D03*
X385679Y147729D03*
X387588Y177616D03*
X388169Y172190D03*
X382025Y188727D03*
X387611Y265896D03*
X382524Y265701D03*
X392627Y266114D03*
X384159Y281716D03*
X390100Y281982D03*
X390905Y290755D03*
X384173Y379028D03*
X381237Y371076D03*
X394237Y379591D03*
X396373Y407104D03*
X393893Y413611D03*
X393833Y423944D03*
X393646Y474382D03*
X385634Y472020D03*
X385694Y477318D03*
X385293Y466409D03*
X385131Y487382D03*
X381875Y740341D03*
X380331Y782627D03*
X392584Y875845D03*
X384856Y947987D03*
X383710Y1007283D03*
X382465Y1012430D03*
X392234Y1369579D03*
Y1364501D03*
X389466Y1497520D03*
X383259Y1487792D03*
X382896Y1494984D03*
X390449Y1491362D03*
X391740Y1545629D03*
Y1540529D03*
X395296Y1561024D03*
X391740Y1550729D03*
Y1555829D03*
X410789Y22627D03*
X397731Y100625D03*
X405912Y172665D03*
X405739Y183834D03*
X405849Y178560D03*
X399984Y192490D03*
X405259Y190185D03*
X406029Y200864D03*
X406118Y212455D03*
X406052Y207037D03*
X410927Y228631D03*
X396986Y281307D03*
X410086Y336795D03*
X409655Y331589D03*
X410688Y344736D03*
X409994Y351045D03*
X411007Y356743D03*
X405801Y475560D03*
X405301Y467560D03*
X404468Y864407D03*
X406770Y869767D03*
X405466Y881299D03*
X397431Y870654D03*
X401108Y878487D03*
X405179Y959051D03*
X397252Y962861D03*
X396671Y968287D03*
X401063Y1233428D03*
X405063Y1225428D03*
X409063Y1233428D03*
X404324Y1271889D03*
X403798Y1305859D03*
X412663Y1321462D03*
X398456Y1330464D03*
X405294Y1367752D03*
X408773Y1399659D03*
X399373Y1555855D03*
X410034Y1555416D03*
X405496Y1561024D03*
X400396D03*
X410596D03*
X422450Y30483D03*
X414145Y27486D03*
X413904Y32569D03*
X414739Y186778D03*
X414658Y208864D03*
X422988Y323627D03*
X426457Y317115D03*
X426830Y359026D03*
X418435Y351552D03*
X416574Y357528D03*
X421413Y359053D03*
X426647Y452987D03*
X421267Y452799D03*
X414910Y448931D03*
X418801Y474513D03*
X424731Y508152D03*
X427693Y498943D03*
X424993Y728291D03*
X422430Y834800D03*
X425062Y883981D03*
X419987Y1098518D03*
X423340Y1104335D03*
X417063Y1225428D03*
X425063Y1237428D03*
X420830Y1273658D03*
X420922Y1320604D03*
X417305Y1355108D03*
X422875Y1362304D03*
X428084Y1378718D03*
X424376Y1390794D03*
X415421Y1532278D03*
X421454Y1544625D03*
X422539Y1534361D03*
X426701Y1541947D03*
X437386Y143740D03*
X434766Y148277D03*
X436666Y322583D03*
X434927Y317228D03*
X443424Y332988D03*
X440538Y355372D03*
X438098Y442114D03*
X437835Y435101D03*
X432270Y431112D03*
X432440Y440101D03*
X432075Y452718D03*
X438086Y452601D03*
X438078Y447121D03*
X438396Y511493D03*
X443144Y628667D03*
X441162Y638313D03*
X443091Y1026266D03*
X429063Y1225428D03*
X441220Y1271776D03*
X436191Y1271753D03*
X437644Y1296834D03*
X432644D03*
X435705Y1302380D03*
X441153Y1319961D03*
X438549Y1329943D03*
X433318Y1357671D03*
X431127Y1365203D03*
X450436Y143518D03*
X449536Y152373D03*
X446566Y337917D03*
X450852Y372054D03*
X459414Y468689D03*
X459757Y463520D03*
X459461Y473805D03*
X459929Y491669D03*
X460537Y501905D03*
X459952Y496842D03*
X459645Y509486D03*
X447279Y637031D03*
X447921Y630789D03*
X453552Y631779D03*
X460498Y870334D03*
X459360Y996755D03*
Y1012325D03*
X459885Y1018860D03*
X451140Y1021793D03*
X450875Y1028416D03*
X455591Y1015825D03*
X452091Y1039880D03*
X459700Y1032266D03*
X452115Y1098518D03*
X455468Y1104335D03*
X457510Y1224106D03*
X459560Y1239245D03*
X460567Y1230219D03*
X456472Y1271860D03*
X451377Y1271840D03*
X446246Y1271785D03*
X448349Y1314391D03*
X474307Y102249D03*
X474058Y116594D03*
X473032Y110784D03*
X468032D03*
X477592Y125107D03*
X462523Y124283D03*
X467589Y124879D03*
X472611Y124663D03*
X473955Y138838D03*
X475407Y195176D03*
X472226Y201683D03*
X475293Y244571D03*
X472673Y249108D03*
X467335Y359944D03*
X469530Y366754D03*
X473658Y470509D03*
Y475509D03*
X468558Y491669D03*
X468850Y545586D03*
X464776Y636506D03*
X461626Y648827D03*
X474540Y927341D03*
X475018Y992568D03*
X467345Y996480D03*
X464891Y1019069D03*
X473954Y1027202D03*
X464385Y1038534D03*
X471755Y1038665D03*
X470610Y1033783D03*
X475588Y1043055D03*
X470978Y1046591D03*
X469772Y1224717D03*
X469053Y1238094D03*
X467507Y1230974D03*
X461677Y1271882D03*
X467007Y1271914D03*
X472624Y1271807D03*
X463290Y1297035D03*
X492135Y103411D03*
X492529Y97667D03*
X483675D03*
X486206Y143762D03*
X480106Y148717D03*
X489672Y199248D03*
X493272Y230117D03*
X484427Y230556D03*
X488682Y227824D03*
X479686Y228646D03*
X490989Y244297D03*
X482636Y256394D03*
X492817Y357111D03*
X491843Y351089D03*
X490885Y373589D03*
X491053Y365423D03*
X491289Y391589D03*
X490885Y382570D03*
X488438Y418417D03*
X481485Y439900D03*
Y431917D03*
X489485Y431417D03*
X492736Y478982D03*
Y491982D03*
X491818Y534909D03*
X491445Y541135D03*
X482905Y544726D03*
X491534Y552726D03*
X491511Y546553D03*
X493392Y622285D03*
X493580Y616905D03*
X493661Y627713D03*
X493778Y633724D03*
X483059Y662649D03*
X481742Y657477D03*
X482476Y798164D03*
X490706Y859339D03*
X491616Y938771D03*
X479613Y952189D03*
X480711Y999941D03*
X477857Y1004375D03*
X488794Y1024081D03*
X479735Y1032551D03*
X485633Y1036155D03*
X477765Y1093432D03*
X485574Y1098518D03*
X488927Y1104335D03*
X478133Y1271807D03*
X489153Y1271591D03*
X483535Y1271699D03*
X503325Y90650D03*
X508637Y90615D03*
X496023Y362913D03*
X497048Y369450D03*
X495750Y377531D03*
X506500Y379687D03*
X495203Y386890D03*
X503682Y448419D03*
X504729Y469905D03*
X496729Y461919D03*
X504729Y461419D03*
X501224Y492050D03*
X501649Y482165D03*
X500890Y500202D03*
X502493Y495917D03*
X506925Y546830D03*
X497448Y610548D03*
X504265Y633736D03*
X499258Y633716D03*
X506278Y628078D03*
X499278Y641817D03*
X499528Y657843D03*
X496176Y684973D03*
X504508Y783817D03*
X507241Y802149D03*
X495539Y795000D03*
X504641Y789139D03*
X507095Y814784D03*
X507741Y807973D03*
X509665Y824512D03*
X503383Y863025D03*
X498507Y865392D03*
X508248Y873319D03*
X509791Y881932D03*
X509017Y905295D03*
X498435Y1008766D03*
X498524Y997590D03*
X498585Y1016266D03*
X506562Y1238194D03*
X498562Y1226194D03*
Y1242194D03*
X494901Y1273083D03*
X500334Y1273157D03*
X506026Y1273542D03*
X521916Y92874D03*
X512958Y99961D03*
X523867Y169454D03*
X516367D03*
X522276Y223661D03*
X519638Y314346D03*
X512943Y443071D03*
X520823Y442603D03*
X518240Y459371D03*
X512210Y475825D03*
X513310Y462004D03*
X522756Y461818D03*
X513626Y528578D03*
X518416Y544895D03*
X520945Y590801D03*
X520770Y597130D03*
X524770Y605637D03*
X523596Y628242D03*
X515267Y627908D03*
X511278Y633473D03*
X514585Y681325D03*
X520277Y682624D03*
X516973Y713088D03*
X512239Y708434D03*
X511677Y712798D03*
X513504Y755804D03*
X513278Y783286D03*
X526171Y801205D03*
X519891Y795848D03*
X520741Y805149D03*
X524741Y845149D03*
X520870Y874694D03*
X516044Y880162D03*
X520685Y887763D03*
X511025Y911443D03*
X525159Y913818D03*
X516902Y910251D03*
X524475Y952290D03*
X522544Y992854D03*
X512232Y985172D03*
X521055Y1104335D03*
X514562Y1230194D03*
X511876Y1272083D03*
X535984Y79592D03*
X528484D03*
X540751Y97475D03*
X539748Y143740D03*
X537128Y148277D03*
X538170Y172190D03*
X537589Y177616D03*
X532026Y188727D03*
X529148Y208695D03*
X528783Y226141D03*
X532525Y265701D03*
X537612Y265896D03*
X534160Y281716D03*
X540101Y281982D03*
X540906Y290755D03*
X532659Y359557D03*
X526388Y351301D03*
X531612Y354272D03*
X531636Y349057D03*
X528812Y369164D03*
X533211Y364746D03*
X533115Y371856D03*
X530144Y376062D03*
X531953Y380749D03*
X542034Y392209D03*
X541706Y386223D03*
X533189Y390723D03*
X531953Y385749D03*
X535119Y483886D03*
X541572Y556742D03*
X535219Y566797D03*
X535819Y578405D03*
X541245Y578986D03*
X534820Y596782D03*
X540770Y596729D03*
X529601Y596089D03*
X536810Y691203D03*
X536087Y702364D03*
X528653Y708952D03*
X542275Y760782D03*
X539449Y782389D03*
X537578Y772428D03*
X539852Y788099D03*
X530741Y845149D03*
X531076Y913190D03*
X532812Y1273169D03*
X538572Y1289143D03*
X547732Y100625D03*
X552798Y143518D03*
X551898Y152373D03*
X555850Y178560D03*
X555913Y172665D03*
X555740Y183834D03*
X555260Y190185D03*
X549985Y192490D03*
X556030Y200864D03*
X556119Y212455D03*
X556053Y207037D03*
X542628Y266114D03*
X546987Y281307D03*
X551620Y390723D03*
X553563Y384987D03*
X543760Y565997D03*
X547861Y692583D03*
X557751Y750851D03*
X550901Y789509D03*
X544515Y793875D03*
X544741Y809649D03*
X544878Y816309D03*
X556741Y820149D03*
X544741Y823149D03*
X552711Y840120D03*
X557836Y851669D03*
X543001Y874859D03*
X546940Y871389D03*
X547843Y892969D03*
X548327Y905295D03*
X553335Y905405D03*
X552923Y988813D03*
X544719Y1007522D03*
X551485Y1006648D03*
X548852Y1018307D03*
X545094Y1013678D03*
X545566Y1023731D03*
X554696Y1018469D03*
X557681Y1035088D03*
X543621Y1292726D03*
X557584Y1543411D03*
X560573Y60513D03*
X569114Y86012D03*
X565207Y94279D03*
X570394Y110784D03*
X574973Y124663D03*
X564885Y124283D03*
X569951Y124879D03*
X574588Y201683D03*
X564659Y208864D03*
X560928Y228631D03*
X575035Y249108D03*
X573479Y374705D03*
X574625Y547918D03*
X563200Y739600D03*
X571493Y763090D03*
X564362Y757979D03*
X560263Y782207D03*
X567126Y779066D03*
X571984Y784507D03*
X560762Y791422D03*
X564388Y839899D03*
X561134Y869291D03*
X559214Y897425D03*
X567827Y884000D03*
X565003Y936807D03*
X570603Y957207D03*
X560923Y988813D03*
X568923D03*
X567484Y1024003D03*
X566058Y1109564D03*
X560211Y1134764D03*
Y1165091D03*
X566502Y1202103D03*
X575620Y1207737D03*
X569135Y1214372D03*
X564890Y1218169D03*
X570796Y1530309D03*
X563968Y1541445D03*
X568279Y1538438D03*
X572507Y1541375D03*
X576669Y102249D03*
X586037Y97667D03*
X575394Y110784D03*
X579954Y125107D03*
X582468Y148717D03*
X576317Y138838D03*
X577769Y195176D03*
X585016Y198733D03*
X586789Y230556D03*
X591044Y227824D03*
X582048Y228646D03*
X577655Y244571D03*
X584998Y256394D03*
X578193Y336391D03*
X584679Y336285D03*
X577638Y769772D03*
X578271Y763556D03*
X583102Y767137D03*
X587183Y785008D03*
X578204Y775137D03*
X585912Y778470D03*
X588659Y790336D03*
X588501Y811048D03*
X577501Y811548D03*
X582737Y819831D03*
X580327Y892000D03*
X586136Y908935D03*
X586103Y961807D03*
X584923Y988813D03*
X576923D03*
X581166Y1021954D03*
X577704Y1029427D03*
X587880Y1034834D03*
X587467Y1105091D03*
X582012Y1102091D03*
X587467Y1117691D03*
X582012Y1127291D03*
Y1114691D03*
X587467Y1130291D03*
Y1142891D03*
X582012Y1139891D03*
X587467Y1155491D03*
X582012Y1152491D03*
X587467Y1168091D03*
X582012Y1165091D03*
X587467Y1180691D03*
X582012Y1177691D03*
X583520Y1230407D03*
X581803Y1493687D03*
X578859Y1497758D03*
X588859Y1490895D03*
X590826Y1495688D03*
X588507Y1514141D03*
X582027Y1502800D03*
X581803Y1509687D03*
X577931Y1505687D03*
X575809Y1532912D03*
X587809Y1528389D03*
X583809Y1533025D03*
X579809Y1528163D03*
X587809Y1545854D03*
X583809Y1541607D03*
X577571Y1544013D03*
X594497Y103411D03*
X594891Y97667D03*
X605687Y90650D03*
X592034Y199248D03*
X595634Y230117D03*
X593351Y244297D03*
X603554Y250783D03*
X605147Y378600D03*
X602462Y458711D03*
X597517Y546805D03*
X605011Y615600D03*
X604715Y914640D03*
X591754Y956979D03*
X606142Y965665D03*
X597556Y965829D03*
X600923Y988813D03*
X592923D03*
X599113Y1012354D03*
X593658Y1009354D03*
X599113Y1024954D03*
X593658Y1021954D03*
X606434Y1041904D03*
X597026Y1224472D03*
X592991Y1215035D03*
X594183Y1220068D03*
X592885Y1229402D03*
X592634Y1234921D03*
X591487Y1501687D03*
X591481Y1509313D03*
X595809Y1532133D03*
Y1546214D03*
X591809Y1542407D03*
X610999Y90615D03*
X615320Y99961D03*
X618729Y169454D03*
X613401Y242913D03*
X618801Y546062D03*
X616923Y988813D03*
X608923D03*
X612923Y997860D03*
X607993Y1036920D03*
X610780Y1051037D03*
X613386Y1143390D03*
X622736Y1151870D03*
Y1159350D03*
X613738Y1546507D03*
X628153Y81611D03*
X635653D03*
X624278Y92874D03*
X639490Y148277D03*
X626229Y169454D03*
X639951Y177616D03*
X634388Y188727D03*
X631510Y208695D03*
X624638Y223661D03*
X631145Y226141D03*
X639974Y265896D03*
X634887Y265701D03*
X636522Y281716D03*
X632071Y1142487D03*
X624594Y1146271D03*
X626476Y1155610D03*
X626073Y1170092D03*
X624606Y1164960D03*
X639565Y1194917D03*
X650094Y100625D03*
X643113Y97475D03*
X655160Y143518D03*
X642110Y143740D03*
X654260Y152373D03*
X640532Y172190D03*
X652347Y192490D03*
X647547Y231021D03*
X644990Y266114D03*
X649349Y281307D03*
X642463Y281982D03*
X643268Y290755D03*
X642414Y545528D03*
X656026Y551040D03*
X650958Y668153D03*
X643271Y1135040D03*
X650787Y1217322D03*
X662935Y60513D03*
X671476Y86012D03*
X667569Y94279D03*
X658756Y103621D03*
X667247Y124283D03*
X672313Y124879D03*
X658275Y172665D03*
X658212Y178560D03*
X658102Y183834D03*
X657622Y190185D03*
X658392Y200864D03*
X667021Y208864D03*
X658481Y212455D03*
X658415Y207037D03*
X663290Y228631D03*
X661761Y382109D03*
X661760Y551683D03*
X660586Y606929D03*
X665086Y604567D03*
X665586Y595500D03*
X660827Y612592D03*
X666244Y610072D03*
X660546Y618400D03*
X666180Y616317D03*
X665643Y646055D03*
X658064Y650119D03*
X669488Y1209842D03*
X662008Y1217322D03*
X669488D03*
X679031Y102249D03*
X688399Y97667D03*
X677756Y110784D03*
X672756D03*
X682316Y125107D03*
X677335Y124663D03*
X684830Y148717D03*
X678679Y138838D03*
X680131Y195176D03*
X687378Y198733D03*
X676950Y201683D03*
X684410Y228646D03*
X677397Y249108D03*
X680017Y244571D03*
X682857Y339477D03*
X687055Y376456D03*
X685353Y404718D03*
Y412718D03*
X672586Y544000D03*
X680586Y568000D03*
X681256Y1055975D03*
X687408Y1050045D03*
X682088Y1062847D03*
X673228Y1213582D03*
X696859Y103411D03*
X697253Y97667D03*
X690930Y143762D03*
X694396Y199248D03*
X697996Y230117D03*
X689151Y230556D03*
X693406Y227824D03*
X695713Y244297D03*
X690504Y253198D03*
X689486Y339583D03*
X692356Y764614D03*
X691991Y759581D03*
X692155Y778974D03*
X692221Y773449D03*
X697684Y1053324D03*
X690085Y1058763D03*
X701899Y1633858D03*
X708049Y90650D03*
X713361Y90615D03*
X717682Y99961D03*
X721091Y169454D03*
X712692Y356779D03*
X717105Y410964D03*
X717420Y404334D03*
X709781Y442956D03*
X720996Y442856D03*
X715733Y447055D03*
X719051Y458455D03*
X719612Y451108D03*
X706211Y465874D03*
X711463Y546712D03*
X713425Y786029D03*
X707252Y1055787D03*
X707492Y1633514D03*
X713002Y1637887D03*
X729842Y81274D03*
X737342D03*
X726640Y92874D03*
X728591Y169454D03*
X736750Y188727D03*
X733872Y208695D03*
X733507Y226141D03*
X727000Y223661D03*
X737249Y265701D03*
X723404Y379657D03*
X721900Y384500D03*
X723440Y391496D03*
X734661Y393633D03*
X723440Y398583D03*
X728503Y891692D03*
X736452Y890548D03*
X728692Y886653D03*
X725194Y942073D03*
X733798Y950186D03*
X722820Y1064608D03*
X726823Y1263349D03*
X736067Y1611892D03*
X729600Y1625165D03*
X732268Y1618260D03*
X752456Y100625D03*
X745475Y97475D03*
X744472Y143740D03*
X741852Y148277D03*
X742894Y172190D03*
X742313Y177616D03*
X747352Y266114D03*
X742336Y265896D03*
X751711Y281307D03*
X744825Y281982D03*
X738884Y281716D03*
X745630Y290755D03*
X749444Y393858D03*
X745586Y388000D03*
X752785Y382047D03*
X753086Y403500D03*
X751086Y398583D03*
X739316Y458572D03*
X744069Y746617D03*
X742000Y768137D03*
X738707Y987952D03*
X745673Y1007009D03*
X743200Y1128100D03*
X748031Y1142519D03*
X744291Y1149999D03*
X753099Y1185514D03*
X753537Y1178467D03*
X749786Y1590517D03*
X738775Y1597866D03*
X749704Y1608631D03*
X765297Y60513D03*
X769931Y94279D03*
X769609Y124283D03*
X757522Y143518D03*
X756622Y152373D03*
X760637Y172665D03*
X760464Y183834D03*
X760574Y178560D03*
X754709Y192490D03*
X759984Y190185D03*
X760754Y200864D03*
X769383Y208864D03*
X760843Y212455D03*
X760777Y207037D03*
X769349Y324518D03*
X754805Y339559D03*
X759624Y353961D03*
X756086Y377912D03*
X755086Y391496D03*
X756086Y386500D03*
X756174Y397912D03*
X755086Y409000D03*
X767585Y433666D03*
X765105Y572830D03*
Y600537D03*
X757721Y617468D03*
X755512Y1112598D03*
X766732Y1142519D03*
X760398Y1440276D03*
X763542Y1590186D03*
X767310Y1599164D03*
X768361Y1610083D03*
X756358Y1616917D03*
X773838Y86012D03*
X781393Y102249D03*
X775118Y110784D03*
X780118D03*
X784678Y125107D03*
X779697Y124663D03*
X774675Y124879D03*
X781041Y138838D03*
X782493Y195176D03*
X779312Y201683D03*
X774432Y218085D03*
X782379Y244571D03*
X779759Y249108D03*
X772165Y314890D03*
X784118Y303962D03*
X772162Y332584D03*
X778502Y348015D03*
X772859Y347937D03*
X784902Y428653D03*
X780782Y433440D03*
X783620Y1460108D03*
X781110Y1595254D03*
X777059Y1608982D03*
X784046Y1600438D03*
X799221Y103411D03*
X799615Y97667D03*
X790761D03*
X793292Y143762D03*
X787192Y148717D03*
X796758Y199248D03*
X789740Y198733D03*
X800358Y230117D03*
X795768Y227824D03*
X791513Y230556D03*
X786772Y228646D03*
X798075Y244297D03*
X789722Y256394D03*
X786461Y293028D03*
X790280Y287421D03*
X795445Y356950D03*
X789581Y405011D03*
X793893Y409502D03*
X802136Y448334D03*
X794733Y915483D03*
X797178Y922746D03*
X800018Y934000D03*
X792575Y932815D03*
X793810Y1013122D03*
X801043Y1010773D03*
X796338Y1138130D03*
X797160Y1146609D03*
X792277Y1173065D03*
X799020Y1175975D03*
X792382Y1191664D03*
X788208Y1208014D03*
X796777Y1206299D03*
X790587Y1202200D03*
X790749Y1196138D03*
X791986Y1224512D03*
X788327Y1221062D03*
X802394Y1221197D03*
X794971Y1233951D03*
X800262Y1237535D03*
X788102Y1232283D03*
X793548Y1397690D03*
X799330Y1416760D03*
X789647Y1427518D03*
X798601Y1431673D03*
X793288Y1450918D03*
X787694Y1442749D03*
X800607Y1440760D03*
X793994Y1441499D03*
X797083Y1467883D03*
X794005Y1464178D03*
X786591Y1452803D03*
X810411Y90650D03*
X815723Y90615D03*
X817456Y305368D03*
Y313368D03*
X809490Y305368D03*
X809466Y310604D03*
X817100Y319600D03*
X809457Y330459D03*
X809490Y325368D03*
Y317368D03*
X810749Y443045D03*
X810453Y453330D03*
X810406Y448214D03*
X813678Y740979D03*
X817584Y764219D03*
X818000Y797000D03*
X817845Y817879D03*
X818500Y810135D03*
X815863Y830097D03*
X814299Y840877D03*
X813887Y835146D03*
X816037Y845578D03*
X817884Y915425D03*
X806168Y910166D03*
X803507Y926197D03*
X817229Y935344D03*
X818070Y972723D03*
X809632Y1142666D03*
X817964Y1157404D03*
X811507Y1157544D03*
X810018Y1167768D03*
X815037D03*
X814170Y1185205D03*
X805212Y1180175D03*
X805519Y1187215D03*
X816284Y1197626D03*
X804458Y1193112D03*
X817446Y1210089D03*
X812405Y1228760D03*
X806148Y1383715D03*
Y1375208D03*
X810204Y1401661D03*
X804654Y1404769D03*
X805569Y1441519D03*
X802684Y1465549D03*
X807576Y1469584D03*
X834559Y80265D03*
X829002Y92874D03*
X820044Y99961D03*
X823453Y169454D03*
X830953D03*
X829362Y223661D03*
X822160Y258880D03*
X822477Y309368D03*
X829485Y345101D03*
X822626Y348066D03*
X818840Y444091D03*
X824650Y455034D03*
Y450034D03*
X832284Y731216D03*
X821582Y727140D03*
X830484Y738750D03*
X830075Y769000D03*
X824500Y756000D03*
Y774000D03*
Y782500D03*
X830075Y787000D03*
X824342Y792315D03*
X824500Y800500D03*
X830075Y805000D03*
Y823000D03*
X829757Y842672D03*
X822916Y852576D03*
X823540Y857956D03*
X831654Y864494D03*
X822938Y863298D03*
X828835Y854920D03*
X833194Y873561D03*
X827992Y874107D03*
X830063Y898500D03*
X819918Y889365D03*
X824804Y898395D03*
X829848Y914211D03*
X825336Y916774D03*
X834751Y922368D03*
X833683Y936743D03*
X824414Y939655D03*
X822829Y960614D03*
X832432Y977982D03*
X829517Y1010303D03*
X823549Y1009583D03*
X825744Y1146937D03*
X818879Y1187310D03*
X823309Y1180235D03*
X823516Y1185238D03*
X819419Y1230265D03*
X826204Y1440689D03*
X826341Y1451236D03*
X826365Y1458974D03*
X842059Y80265D03*
X847837Y97475D03*
X844675Y177616D03*
X845256Y172190D03*
X839112Y188727D03*
X836234Y208695D03*
X835869Y226141D03*
X844698Y265896D03*
X839611Y265701D03*
X849714Y266114D03*
X841246Y281716D03*
X847187Y281982D03*
X847992Y290755D03*
X845435Y356172D03*
X849591Y411388D03*
X842515Y461382D03*
X850732Y469382D03*
X842779Y473076D03*
X842916Y467009D03*
X848444Y657756D03*
X837272Y663910D03*
X842352Y659243D03*
X845850Y710969D03*
X836078Y709619D03*
X848284Y731181D03*
X846484Y738750D03*
X836713Y738751D03*
X844520Y791925D03*
X835215Y847719D03*
X835346Y891346D03*
X843665Y907110D03*
X841689Y941243D03*
X842856Y949146D03*
X843734Y1008778D03*
X843650Y1449546D03*
X835474Y1457397D03*
X854818Y100625D03*
X862826Y183834D03*
X862999Y172665D03*
X862936Y178560D03*
X857071Y192490D03*
X862346Y190185D03*
X863116Y200864D03*
X863205Y212455D03*
X863139Y207037D03*
X852271Y231021D03*
X866015Y224536D03*
X854073Y281307D03*
X863430Y309368D03*
Y316970D03*
X863114Y324505D03*
X863040Y330140D03*
X860586Y383000D03*
X861235Y394000D03*
X854086Y392999D03*
X855017Y411969D03*
X867093Y570703D03*
Y582828D03*
X861663Y646653D03*
X855300Y646819D03*
X853982Y657506D03*
X859441Y678015D03*
X864029Y688970D03*
X858186Y713170D03*
X867455Y710611D03*
X858002Y707244D03*
X867227Y722060D03*
X859199Y744517D03*
X854484Y738633D03*
X859000Y756000D03*
X854758Y766075D03*
X852710Y755925D03*
X859000Y774000D03*
X853837Y784075D03*
X851584Y773925D03*
X859000Y792000D03*
X853837Y802075D03*
X859000Y810000D03*
X853851Y818000D03*
X852250Y809925D03*
X856992Y829054D03*
X863206Y864154D03*
X865218Y853311D03*
X867310Y873743D03*
X861771Y874368D03*
X863631Y883459D03*
X862868Y891471D03*
X858988Y898307D03*
X867096Y935963D03*
X858601Y934505D03*
X853030Y934690D03*
X851925Y951350D03*
X860887Y1023208D03*
X867659Y60513D03*
X876200Y86012D03*
X867787Y85731D03*
X872293Y94279D03*
X872816Y244389D03*
X883118Y262687D03*
X873262Y300030D03*
X869924Y305368D03*
Y313368D03*
Y321368D03*
Y328722D03*
X874005Y344917D03*
X870413Y342791D03*
X869924Y333722D03*
X877909Y391731D03*
X882925Y391099D03*
X872736Y391754D03*
X867586Y393000D03*
X868586Y398500D03*
X874253Y420080D03*
X869454Y479303D03*
X869954Y487303D03*
X882954Y486256D03*
X882195Y539204D03*
X872264Y558530D03*
X883525Y554619D03*
X878382Y554942D03*
X876949Y571419D03*
X872264Y566530D03*
Y562530D03*
X881476Y588202D03*
X881131Y577349D03*
X877400Y584126D03*
X875290Y578703D03*
X878881Y667156D03*
X880501Y710611D03*
X873021Y715729D03*
X879875Y753612D03*
X873728Y752692D03*
X874851Y769017D03*
X880054Y769358D03*
X870017Y757313D03*
X874807Y784757D03*
X870000Y780000D03*
X879887Y784719D03*
X880040Y792851D03*
X881753Y833087D03*
X869886Y846907D03*
X869609Y841429D03*
X880404Y839742D03*
X875820Y843856D03*
X875171Y850086D03*
X870108Y862191D03*
X876751Y865038D03*
X878246Y859995D03*
X873845Y855576D03*
X870300Y881119D03*
X871876Y869076D03*
X873432Y874571D03*
X879286Y895183D03*
X877080Y887376D03*
X868945Y887459D03*
X871600Y898584D03*
X883286Y901937D03*
X876481Y941126D03*
X872126Y934766D03*
X870209Y949384D03*
X869741Y1025895D03*
X869902Y1079077D03*
X875600Y1096200D03*
X875321Y1207654D03*
X883142Y1259935D03*
X878244Y1451605D03*
X879174Y1459551D03*
X894472Y143740D03*
X891852Y148277D03*
X895064Y250186D03*
X885884Y255118D03*
X897004Y257480D03*
X892484Y260860D03*
X886496Y268968D03*
X886059Y284644D03*
X885953Y321368D03*
Y333368D03*
X888812Y357372D03*
X890553Y392038D03*
X889219Y426952D03*
X891699Y420445D03*
X885556Y543664D03*
X890274Y565040D03*
X894274D03*
X895933Y609696D03*
X886836Y729778D03*
X886610Y769419D03*
X890722Y777118D03*
X884894Y784778D03*
X892040Y784511D03*
X898737Y792289D03*
X889516Y792851D03*
X886065Y828112D03*
X890254Y835978D03*
X891386Y899501D03*
X887286Y896235D03*
X897623Y902409D03*
X891367Y941126D03*
X885099Y1021685D03*
X887862Y1088067D03*
X894004Y1081231D03*
X889033Y1134078D03*
X889967Y1147844D03*
X888650Y1199622D03*
X894713Y1210419D03*
X898878Y1214182D03*
X899286Y1219469D03*
X892532Y1220112D03*
X897169Y1225259D03*
X889244Y1444859D03*
X907522Y143518D03*
X906622Y152373D03*
X915653Y307438D03*
X905483Y355262D03*
X905000Y362158D03*
X906161Y367191D03*
X910646Y376084D03*
X906344Y372524D03*
X910236Y465272D03*
X914296Y558143D03*
X913728Y550495D03*
X908846Y560124D03*
X910789Y598726D03*
X912462Y683770D03*
Y695770D03*
X913247Y714204D03*
X909038Y806465D03*
X914577Y827133D03*
X902630Y828027D03*
X915095Y838701D03*
X911286Y899612D03*
X911487Y894491D03*
X914199Y890063D03*
X906586Y900841D03*
X900983Y940895D03*
X906909Y951494D03*
X909811Y962400D03*
X902389Y1081764D03*
X908799Y1093659D03*
Y1088659D03*
X908278Y1083484D03*
X908799Y1100659D03*
X902353Y1104333D03*
X903959Y1207823D03*
X906784Y1216607D03*
X931393Y102249D03*
X930118Y110784D03*
X925118D03*
X924675Y124879D03*
X929697Y124663D03*
X919609Y124283D03*
X931041Y138838D03*
X929978Y186854D03*
X923732Y304585D03*
X923311Y349959D03*
X921343Y376888D03*
X916330Y377748D03*
X929947Y376821D03*
X927766Y456442D03*
X927596Y447453D03*
X921973Y469328D03*
X927401Y469059D03*
X916593Y469140D03*
X917811Y544325D03*
X921306Y567295D03*
X927288Y567117D03*
X923642Y561578D03*
X923599Y581578D03*
X920165Y594914D03*
X930450Y603319D03*
X929790Y828603D03*
X921127Y833588D03*
X927867Y823081D03*
X921916Y822095D03*
X919702Y826833D03*
X930884Y848974D03*
X925072Y842031D03*
X930626Y842386D03*
X931145Y865672D03*
X931826Y874531D03*
X922475Y894575D03*
X917770Y897618D03*
X923892Y889077D03*
X929181Y895029D03*
X931597Y900701D03*
X916628Y918042D03*
X928628D03*
X929741Y967006D03*
X924956Y994321D03*
X924864Y1023208D03*
X916749Y1092664D03*
X930754Y1310564D03*
X925909Y1413070D03*
X940761Y97667D03*
X934678Y125107D03*
X943292Y143762D03*
X937192Y148717D03*
X933159Y180347D03*
X947424Y184419D03*
X940406Y183904D03*
X946234Y213390D03*
X942179Y215727D03*
X937438Y213817D03*
X936962Y249807D03*
X944248Y239844D03*
X934128Y355168D03*
X944238Y360828D03*
X936175Y364823D03*
X933424Y458455D03*
X933161Y451442D03*
X933404Y463462D03*
X933412Y468942D03*
X948532Y541135D03*
X939992Y544726D03*
X948598Y546553D03*
X948621Y552726D03*
X935281Y677795D03*
X939314Y707847D03*
X933201Y798297D03*
X946970Y786366D03*
X938357Y808856D03*
X940100Y830700D03*
X933344Y821858D03*
X943382Y835395D03*
X933713Y860799D03*
X937333Y864332D03*
X942194Y891216D03*
X944628Y928101D03*
X933810Y972433D03*
X945671Y982191D03*
X943093Y1021769D03*
X948633Y1078908D03*
X933879Y1079077D03*
X939298Y1207654D03*
X947119Y1259935D03*
X944207Y1320739D03*
X947308Y1325035D03*
X944235Y1406262D03*
X947411Y1443901D03*
X934456Y1479446D03*
X937671Y1492139D03*
X949221Y103411D03*
X949615Y97667D03*
X960411Y90650D03*
X950177Y215730D03*
X948741Y229468D03*
X948785Y242464D03*
X950953Y317947D03*
X962769Y451419D03*
X955816Y464919D03*
X963816Y464419D03*
X958124Y492354D03*
X958736Y482165D03*
X959600Y496486D03*
X957977Y500202D03*
X948905Y534909D03*
X950479Y622285D03*
X954535Y610548D03*
X950667Y616905D03*
X963365Y628078D03*
X961352Y633736D03*
X950865Y633724D03*
X950748Y627713D03*
X956345Y633716D03*
X956365Y641817D03*
X956023Y706907D03*
X963869Y725057D03*
X955950Y734178D03*
X957763Y725336D03*
X957579Y744168D03*
X953837Y763025D03*
X950699Y779711D03*
X949609Y796051D03*
X957487Y798553D03*
X955343Y866850D03*
X964280Y927777D03*
X958567Y927654D03*
X951863Y936168D03*
X957235Y936398D03*
X962329Y936229D03*
X957671Y977921D03*
X949671D03*
X957671Y991564D03*
X953671Y982191D03*
X954937Y1021998D03*
X957981Y1081231D03*
X951839Y1088067D03*
X953010Y1134078D03*
X953944Y1147844D03*
X952627Y1199622D03*
X958690Y1210419D03*
X963263Y1219469D03*
X962855Y1214182D03*
X956509Y1220112D03*
X961146Y1225259D03*
X952395Y1395276D03*
X958585Y1389437D03*
X952035Y1401223D03*
X957947Y1484672D03*
X979002Y92874D03*
X965723Y90615D03*
X970044Y99961D03*
X980953Y169454D03*
X973453D03*
X979362Y223661D03*
X975631Y343112D03*
X972030Y446071D03*
X979910Y445603D03*
X972397Y465004D03*
X977327Y462371D03*
X975868Y527449D03*
X978303Y544895D03*
X978032Y590801D03*
X977857Y597130D03*
X980683Y628242D03*
X972354Y627908D03*
X968365Y633473D03*
X973450Y747280D03*
X974437Y849140D03*
X973510Y834991D03*
X967842Y864801D03*
X970299Y853773D03*
X978880Y869552D03*
X973130Y880162D03*
X977771Y887684D03*
X966813Y904556D03*
X973988Y910038D03*
X965671Y982191D03*
X966366Y1081764D03*
X972776Y1093659D03*
X972255Y1083484D03*
X972776Y1088659D03*
X966330Y1104333D03*
X972776Y1100659D03*
X967936Y1207823D03*
X970761Y1216607D03*
X974985Y1290950D03*
X979996Y1386100D03*
X974882Y1392080D03*
X973806Y1444392D03*
X993743Y78919D03*
X986243D03*
X996834Y143740D03*
X994214Y148277D03*
X995256Y172190D03*
X994675Y177616D03*
X989112Y188727D03*
X986234Y208695D03*
X985869Y226141D03*
X989611Y265701D03*
X994698Y265896D03*
X991246Y281716D03*
X997187Y281982D03*
X987517Y314092D03*
X993552Y318175D03*
X989630Y343862D03*
X983717Y341665D03*
X983956Y346652D03*
X993026Y353813D03*
X981719Y352217D03*
X997059Y348522D03*
X988631Y349496D03*
X989950Y360307D03*
X986373Y370467D03*
X981843Y464818D03*
X992206Y483886D03*
X985699Y480705D03*
X985334Y498151D03*
X982375Y529929D03*
X986268Y532949D03*
X992306Y566797D03*
X992906Y578405D03*
X991907Y596782D03*
X986688Y596089D03*
X986600Y717641D03*
X987461Y745796D03*
X985921Y805135D03*
X994094Y829000D03*
X987702Y829159D03*
X987703Y837159D03*
X992441Y870398D03*
X985554Y913434D03*
X986177Y1367678D03*
X983400Y1381496D03*
X984600Y1386800D03*
X985448Y1398271D03*
X994994Y1444240D03*
X982241Y1489637D03*
X1004818Y100625D03*
X997837Y97475D03*
X1013480Y103621D03*
X1005397Y141247D03*
X1009884Y143518D03*
X1008984Y152373D03*
X1012936Y178560D03*
X1012826Y183834D03*
X1012999Y172665D03*
X1012346Y190185D03*
X1007071Y192490D03*
X1013116Y200864D03*
X1013139Y207037D03*
X1013205Y212455D03*
X999714Y266114D03*
X1004061Y280808D03*
X997992Y290755D03*
X1002580Y309619D03*
X1003181Y323057D03*
X1001105Y318006D03*
X1000411Y555306D03*
X1001926Y565908D03*
X998332Y578986D03*
X997857Y596729D03*
X1013151Y756726D03*
X1013319Y785929D03*
X1006053Y787745D03*
X1012703Y837659D03*
X1001187Y850084D03*
X1002176Y875303D03*
X1005413Y892787D03*
Y905295D03*
X1006619Y933822D03*
X1012219Y954222D03*
X1009564Y988874D03*
X1001805Y1007522D03*
X1008571Y1006648D03*
X1002180Y1013678D03*
X1002652Y1023731D03*
X1005938Y1018307D03*
X998600Y1369200D03*
X999283Y1377400D03*
X998643Y1398271D03*
X998685Y1389915D03*
X1017659Y60513D03*
X1026200Y86012D03*
X1017787Y85731D03*
X1022293Y94279D03*
X1027480Y110784D03*
X1021971Y124283D03*
X1027037Y124879D03*
X1021826Y186778D03*
X1018014Y228631D03*
X1015281Y309620D03*
X1014406Y344620D03*
X1020406Y350772D03*
X1025905Y353890D03*
X1021885Y698974D03*
X1021221Y848712D03*
X1017800Y867065D03*
X1021408Y895008D03*
X1024913Y884000D03*
X1013897Y904950D03*
X1022346Y917669D03*
X1029570Y917718D03*
X1027719Y958822D03*
X1018009Y988813D03*
X1026009D03*
X1024570Y1024003D03*
X1014767Y1035088D03*
X1025143Y1030672D03*
X1023144Y1109564D03*
X1023139Y1184856D03*
X1022420Y1203204D03*
X1026221Y1214372D03*
X1021976Y1218169D03*
X1019391Y1377061D03*
X1020196Y1444492D03*
X1016769Y1489832D03*
X1033755Y102249D03*
X1043123Y97667D03*
X1032480Y110784D03*
X1037040Y125107D03*
X1032059Y124663D03*
X1045654Y143762D03*
X1039554Y148717D03*
X1033403Y138838D03*
X1034855Y195176D03*
X1042102Y198733D03*
X1031674Y201683D03*
X1043875Y230556D03*
X1039134Y228646D03*
X1034741Y244571D03*
X1032121Y249108D03*
X1042084Y256394D03*
X1045650Y300093D03*
X1041783Y321114D03*
X1031259Y350427D03*
X1031712Y547918D03*
X1043016Y782161D03*
X1043425Y830800D03*
X1043626Y836563D03*
X1037527Y836486D03*
X1031813Y850273D03*
X1046045Y841217D03*
X1040822Y841339D03*
X1044390Y861210D03*
X1038363Y875288D03*
X1038010Y902565D03*
X1042009Y988813D03*
X1034009D03*
X1038252Y1021954D03*
X1044553Y1105091D03*
X1039098Y1102091D03*
X1044553Y1117691D03*
X1039098Y1114691D03*
Y1127291D03*
X1044553Y1130291D03*
Y1142891D03*
X1039098Y1139891D03*
X1044553Y1155491D03*
X1039098Y1152491D03*
X1044553Y1168091D03*
X1039098Y1165091D03*
X1044553Y1180691D03*
X1039098Y1177691D03*
X1032831Y1207950D03*
X1040606Y1230407D03*
X1045218Y1444596D03*
X1051583Y103411D03*
X1051977Y97667D03*
X1049120Y199248D03*
X1052720Y230117D03*
X1048130Y227824D03*
X1061387Y343509D03*
X1060679Y356151D03*
X1059549Y458711D03*
X1054604Y546805D03*
X1062098Y615600D03*
X1048314Y833102D03*
X1053392Y832788D03*
X1051550Y823146D03*
X1050358Y837793D03*
X1052500Y841200D03*
X1049087Y856033D03*
X1053909Y855472D03*
X1050009Y988813D03*
X1058009D03*
X1056199Y1012354D03*
X1050744Y1009354D03*
X1056199Y1024954D03*
X1050744Y1021954D03*
X1057212Y1040356D03*
X1049930Y1221407D03*
X1050178Y1214934D03*
X1054295Y1224472D03*
X1049770Y1229402D03*
X1049720Y1234921D03*
X1050944Y1437997D03*
X1062773Y90650D03*
X1068085Y90615D03*
X1072406Y99961D03*
X1075815Y169454D03*
X1076571Y310574D03*
X1075888Y546062D03*
X1063642Y634190D03*
X1066931Y645389D03*
X1065823Y988773D03*
X1074009Y988813D03*
X1070009Y997860D03*
X1065079Y1036920D03*
X1076577Y1041332D03*
X1067866Y1051037D03*
X1070472Y1143390D03*
X1069642Y1445541D03*
X1068861Y1451311D03*
X1085912Y78918D03*
X1093412D03*
X1081364Y92874D03*
X1083315Y169454D03*
X1091474Y188727D03*
X1088596Y208695D03*
X1088231Y226141D03*
X1081724Y223661D03*
X1091973Y265701D03*
X1093608Y281716D03*
X1092554Y340318D03*
X1089145Y1142518D03*
X1081680Y1146271D03*
X1079822Y1151870D03*
X1083562Y1155610D03*
X1079822Y1159350D03*
X1083159Y1170092D03*
X1081692Y1164960D03*
X1084000Y1529600D03*
X1091529Y1528718D03*
X1091525Y1546300D03*
X1091569Y1561300D03*
X1092527Y1579422D03*
X1090469Y1588435D03*
X1083900Y1593206D03*
X1088021Y1606949D03*
X1093778Y1599574D03*
X1086904Y1599004D03*
X1090093Y1628297D03*
X1089474Y1638213D03*
X1100199Y97475D03*
X1107180Y100625D03*
X1107759Y141247D03*
X1099196Y143740D03*
X1096576Y148277D03*
X1097618Y172190D03*
X1109903Y171523D03*
X1097037Y177616D03*
X1109433Y192490D03*
X1102076Y266114D03*
X1097060Y265896D03*
X1106435Y281307D03*
X1099549Y281982D03*
X1100354Y290755D03*
X1105012Y353504D03*
X1099501Y545528D03*
X1104448Y653161D03*
X1108045Y668153D03*
X1100357Y1135040D03*
X1096651Y1194917D03*
X1107873Y1217322D03*
X1107200Y1438914D03*
X1096780Y1526700D03*
X1101402Y1518200D03*
Y1531702D03*
X1098617Y1546183D03*
X1096780Y1535400D03*
X1099371Y1561153D03*
X1100476Y1579318D03*
X1102904Y1566668D03*
X1100233Y1588000D03*
X1098904Y1602138D03*
X1101946Y1614709D03*
X1096941Y1627905D03*
X1105474Y1629450D03*
Y1638426D03*
X1097474Y1637753D03*
X1120021Y60513D03*
X1120149Y85731D03*
X1124655Y94279D03*
X1115842Y103621D03*
X1124333Y124283D03*
X1112246Y143518D03*
X1111346Y152373D03*
X1115188Y183834D03*
X1115298Y178560D03*
X1115361Y172665D03*
X1124075Y192665D03*
X1115478Y200864D03*
X1115501Y207037D03*
X1115567Y212455D03*
X1124107Y208864D03*
X1120376Y228631D03*
X1118848Y382109D03*
X1118847Y551683D03*
X1113113Y551040D03*
X1117673Y606929D03*
X1122673Y595500D03*
X1122173Y604567D03*
X1123331Y610072D03*
X1123267Y616317D03*
X1117633Y618400D03*
X1117914Y612592D03*
X1115151Y650119D03*
X1119094Y1217322D03*
X1126574D03*
Y1209842D03*
X1128562Y86012D03*
X1136117Y102249D03*
X1129842Y110784D03*
X1134842D03*
X1139402Y125107D03*
X1129399Y124879D03*
X1134421Y124663D03*
X1141916Y148717D03*
X1135765Y138838D03*
X1137217Y195176D03*
X1134036Y201683D03*
X1141496Y228646D03*
X1137103Y244571D03*
X1134483Y249108D03*
X1137830Y336230D03*
X1142440Y404718D03*
Y412718D03*
X1135548Y455804D03*
X1129673Y544000D03*
X1137673Y568000D03*
X1138342Y1055975D03*
X1139174Y1062847D03*
X1130314Y1213582D03*
X1153945Y103411D03*
X1145485Y97667D03*
X1154339D03*
X1148016Y143762D03*
X1151482Y199248D03*
X1144464Y198733D03*
X1146237Y230556D03*
X1155082Y230117D03*
X1150492Y227824D03*
X1147590Y253198D03*
X1145587Y339148D03*
X1157251Y636842D03*
X1152485Y764552D03*
X1147468Y766093D03*
X1146674Y778409D03*
X1153485Y813142D03*
X1154985Y802897D03*
X1153229Y848581D03*
X1144494Y1050045D03*
X1154770Y1053324D03*
X1147171Y1058763D03*
X1170447Y90615D03*
X1165135Y90650D03*
X1174768Y99961D03*
X1174284Y443585D03*
X1166868Y442956D03*
X1172172Y433003D03*
X1163298Y465874D03*
X1160756Y665140D03*
X1164732Y802269D03*
X1173122Y802759D03*
X1163579Y850774D03*
X1161535Y844167D03*
X1174461Y914515D03*
X1164338Y1055787D03*
X1189957Y80938D03*
X1183726Y92874D03*
X1178177Y169454D03*
X1185677D03*
X1190958Y208695D03*
X1190593Y226141D03*
X1184086Y223661D03*
X1191748Y392676D03*
X1179184Y403307D03*
X1176699Y451108D03*
X1176138Y458455D03*
X1177566Y778539D03*
X1185516Y844248D03*
X1190968Y848703D03*
X1184340Y851072D03*
X1183012Y856553D03*
X1190213Y856816D03*
X1182602Y879142D03*
X1184652Y886399D03*
X1190431Y888873D03*
X1181151Y919034D03*
X1187871Y916534D03*
X1188219Y951789D03*
X1181438Y978941D03*
X1187714Y984794D03*
X1179906Y1064608D03*
X1191643Y1163114D03*
X1197457Y80938D03*
X1202561Y97475D03*
X1201558Y143740D03*
X1198938Y148277D03*
X1199980Y172190D03*
X1199399Y177616D03*
X1193836Y188727D03*
X1199422Y265896D03*
X1204438Y266114D03*
X1194335Y265701D03*
X1201911Y281982D03*
X1195970Y281716D03*
X1202716Y290755D03*
X1195800Y324000D03*
X1206531Y393858D03*
X1202673Y388000D03*
X1208173Y398583D03*
X1192702Y440489D03*
X1192957Y435158D03*
X1196403Y458572D03*
X1197152Y882399D03*
X1196661Y922901D03*
X1192651Y918534D03*
X1203219Y962789D03*
X1193483Y983053D03*
X1205117Y1112598D03*
X1200313Y1128100D03*
X1205117Y1142519D03*
X1201377Y1149999D03*
X1222383Y60513D03*
X1222511Y85731D03*
X1218204Y103621D03*
X1209542Y100625D03*
X1210121Y141247D03*
X1214608Y143518D03*
X1213708Y152373D03*
X1217550Y183834D03*
X1212265Y171523D03*
X1217723Y172665D03*
X1217660Y178560D03*
X1211795Y192490D03*
X1217840Y200864D03*
X1217863Y207037D03*
X1217929Y212455D03*
X1222738Y228631D03*
X1208797Y281307D03*
X1211892Y339559D03*
X1213173Y377912D03*
Y386500D03*
X1209872Y382047D03*
X1212173Y391496D03*
X1213261Y397912D03*
X1210173Y403500D03*
X1212173Y409000D03*
X1212598Y1112598D03*
X1223818Y1142519D03*
X1210623Y1178467D03*
X1210185Y1185514D03*
X1230924Y86012D03*
X1238479Y102249D03*
X1227017Y94279D03*
X1232204Y110784D03*
X1237204D03*
X1236783Y124663D03*
X1226695Y124283D03*
X1231761Y124879D03*
X1238127Y138838D03*
X1239579Y195176D03*
X1236398Y201683D03*
X1226469Y208864D03*
X1239465Y244571D03*
X1236845Y249108D03*
X1229252Y314890D03*
X1226436Y324518D03*
X1235589Y348015D03*
X1229942Y347937D03*
X1227159Y432124D03*
X1232773Y456559D03*
X1256307Y103411D03*
X1247847Y97667D03*
X1256701D03*
X1241764Y125107D03*
X1250378Y143762D03*
X1244278Y148717D03*
X1253844Y199248D03*
X1246826Y198733D03*
X1248599Y230556D03*
X1252854Y227824D03*
X1243858Y228646D03*
X1246808Y256394D03*
X1241205Y303962D03*
X1252330Y456005D03*
X1254200Y1146600D03*
X1256218Y1175987D03*
X1249363Y1166065D03*
X1255628Y1188345D03*
X1246056Y1205107D03*
X1249072Y1224512D03*
X1245413Y1221062D03*
X1245188Y1232283D03*
X1252057Y1233951D03*
X1254275Y1531334D03*
X1249894Y1527805D03*
X1254275Y1539334D03*
X1250434Y1535334D03*
X1267497Y90650D03*
X1257444Y230117D03*
X1266616Y322456D03*
X1263500Y336000D03*
X1263484Y385644D03*
X1268659Y385123D03*
X1268067Y406060D03*
X1261231Y399918D03*
X1260818Y418996D03*
X1260563Y431730D03*
X1267540Y459330D03*
X1267493Y454214D03*
X1267836Y449045D03*
X1270586Y905324D03*
X1272661Y929858D03*
X1266718Y1142666D03*
X1268593Y1157544D03*
X1267104Y1167768D03*
X1272123D03*
X1271256Y1185205D03*
X1262605Y1187215D03*
X1262298Y1180175D03*
X1260800Y1191096D03*
X1262421Y1195059D03*
X1258237Y1203115D03*
X1273370Y1197626D03*
X1259480Y1221197D03*
X1257348Y1237535D03*
X1269491Y1228760D03*
X1267333Y1531334D03*
X1262891Y1527334D03*
X1267183Y1539334D03*
X1262891Y1535334D03*
X1286088Y92874D03*
X1277130Y99961D03*
X1280539Y169454D03*
X1288039D03*
X1286448Y223661D03*
X1289345Y330655D03*
X1287437Y370010D03*
Y379429D03*
X1273659Y385123D03*
X1280659D03*
X1284333Y391569D03*
X1282760Y409016D03*
X1281737Y461034D03*
Y456034D03*
X1284900Y678800D03*
X1278255Y722241D03*
X1282539Y746076D03*
Y756076D03*
X1279539Y776576D03*
X1281777Y823500D03*
X1285500Y843500D03*
X1281269Y835492D03*
X1285500Y851500D03*
X1279460Y854487D03*
Y859487D03*
Y864487D03*
Y874487D03*
Y879487D03*
X1274264Y898591D03*
X1279460Y884487D03*
X1279299Y898813D03*
X1279460Y889487D03*
X1288500Y904120D03*
X1274400Y914123D03*
X1283493Y929858D03*
X1279693Y919800D03*
X1274670Y919808D03*
X1289547Y941000D03*
X1275050Y1157404D03*
X1275965Y1187232D03*
X1280602Y1185238D03*
X1280395Y1180235D03*
X1275032Y1209589D03*
X1302139Y26325D03*
X1290973Y78245D03*
X1298473D03*
X1304923Y97475D03*
X1301761Y177616D03*
X1302342Y172190D03*
X1296198Y188727D03*
X1293320Y208695D03*
X1292955Y226141D03*
X1296697Y265701D03*
X1301784Y265896D03*
X1304273Y281982D03*
X1298332Y281716D03*
X1305078Y290755D03*
X1292500Y335000D03*
X1299959Y356954D03*
X1299410Y370976D03*
X1293048Y379088D03*
X1298346Y379028D03*
X1293100Y406739D03*
X1299867Y477318D03*
X1299466Y466409D03*
X1299807Y472020D03*
X1299304Y487382D03*
X1301194Y565518D03*
X1305836Y660009D03*
X1298963Y659609D03*
X1289811Y677612D03*
X1303520Y748403D03*
X1291604Y781576D03*
Y776576D03*
Y771435D03*
X1298720Y798975D03*
X1302140Y812625D03*
X1302501Y824747D03*
X1297667Y832150D03*
X1293500Y827500D03*
Y843500D03*
Y835500D03*
X1296687Y839500D03*
X1303628Y841054D03*
X1293500Y851500D03*
X1294000Y863500D03*
X1304050Y874900D03*
X1305250Y889250D03*
X1304000Y884000D03*
X1291129Y892267D03*
X1299895Y896545D03*
X1296466Y903469D03*
X1304949Y928546D03*
X1295453Y928047D03*
X1291059Y917000D03*
X1302000D03*
X1300882Y937144D03*
X1297558Y970216D03*
X1296787Y1291220D03*
X1301769Y1295154D03*
X1314887Y45448D03*
X1311904Y100625D03*
X1320566Y103621D03*
X1319912Y183834D03*
X1314627Y171523D03*
X1320085Y172665D03*
X1320022Y178560D03*
X1314157Y192490D03*
X1320202Y200864D03*
X1320225Y207037D03*
X1320291Y212455D03*
X1309357Y231021D03*
X1306800Y266114D03*
X1311159Y281307D03*
X1313103Y339606D03*
X1312240Y334681D03*
X1308012Y348109D03*
X1320925Y356636D03*
X1315807Y353785D03*
X1308410Y379591D03*
X1310546Y407104D03*
X1308066Y413611D03*
X1308006Y423944D03*
X1307819Y474382D03*
X1319474Y467560D03*
X1319974Y475560D03*
X1319323Y598454D03*
X1319000Y641000D03*
X1313979Y677726D03*
X1319000Y685500D03*
X1321000Y796000D03*
X1313000D03*
X1317000Y799000D03*
X1315000Y811620D03*
X1321000Y804000D03*
X1321972Y825042D03*
X1317276Y826776D03*
X1311277Y837557D03*
X1312359Y845788D03*
X1315104Y852201D03*
X1310678Y856981D03*
X1310125Y863849D03*
X1307500Y880000D03*
X1314641Y874641D03*
X1315603Y889517D03*
X1314500Y911500D03*
Y905000D03*
X1309103Y917000D03*
X1313152Y936605D03*
X1312575Y943974D03*
X1321256Y943815D03*
X1307000Y960500D03*
X1315441Y960000D03*
X1311000Y970124D03*
X1307707Y979870D03*
X1307561Y986951D03*
X1315756Y1039344D03*
X1306385Y1036646D03*
X1319237Y1225428D03*
X1306805Y1279545D03*
X1318287Y1291381D03*
X1324120Y22742D03*
X1328003Y32403D03*
X1328318Y27333D03*
X1336623Y30483D03*
X1328831Y208864D03*
X1325100Y228631D03*
X1322547Y323226D03*
X1332359Y322685D03*
X1331922Y359836D03*
X1335440Y452799D03*
X1329083Y448931D03*
X1332974Y474513D03*
X1326993Y556788D03*
X1327043Y573346D03*
X1327000Y562500D03*
X1326946Y567906D03*
X1338000Y562500D03*
X1335000Y590500D03*
X1327000Y578500D03*
Y583826D03*
Y605000D03*
Y594500D03*
X1333224Y615484D03*
X1327000Y613000D03*
X1335532Y622260D03*
X1338000Y609000D03*
X1335000Y633000D03*
X1327000Y629000D03*
X1327003Y623940D03*
X1338000Y653500D03*
X1327000Y641000D03*
Y657500D03*
Y685500D03*
Y695500D03*
Y700500D03*
X1338000D03*
X1327000Y711500D03*
Y716500D03*
Y732500D03*
X1330295Y746328D03*
X1336661Y753675D03*
Y745675D03*
Y737675D03*
X1330295Y751328D03*
X1330086Y763758D03*
X1324217Y780595D03*
X1336746Y781675D03*
X1329000Y796000D03*
X1325000Y799000D03*
X1337000Y796000D03*
X1333000Y799000D03*
X1330850Y830350D03*
X1331877Y825377D03*
X1337463Y824038D03*
X1326288Y864602D03*
X1332203Y864566D03*
X1323549Y897045D03*
X1336096Y905042D03*
X1338500Y913000D03*
X1326500Y925500D03*
X1333132Y933781D03*
X1336000Y943500D03*
X1323000Y934075D03*
X1326500Y943500D03*
X1325550Y960445D03*
X1334161Y1098518D03*
X1337514Y1104335D03*
X1331237Y1229428D03*
X1335237Y1237428D03*
X1323237D03*
X1332907Y1278568D03*
X1336936Y1278376D03*
X1328903Y1278838D03*
X1351559Y143740D03*
X1348939Y148277D03*
X1344007Y279054D03*
X1347990Y322539D03*
X1341169Y325926D03*
X1349636Y340862D03*
X1346510Y355658D03*
X1349763Y371908D03*
X1346443Y431112D03*
X1352008Y435101D03*
X1352271Y442114D03*
X1346613Y440101D03*
X1352251Y447121D03*
X1346248Y452718D03*
X1340820Y452987D03*
X1352259Y452601D03*
X1346738Y564492D03*
X1339289Y568461D03*
X1342053Y579339D03*
X1346533Y576780D03*
X1340522Y586133D03*
X1343000Y590458D03*
X1346533Y581898D03*
X1344129Y606914D03*
X1344433Y601201D03*
X1339289Y614961D03*
X1344680Y619085D03*
X1346738Y611192D03*
X1346533Y628398D03*
X1342053Y625839D03*
X1340522Y632633D03*
X1343000Y636958D03*
X1346738Y655492D03*
X1339289Y659461D03*
X1346533Y667780D03*
X1342053Y670339D03*
X1346533Y672898D03*
X1340522Y677133D03*
X1343000Y681458D03*
X1350929Y687043D03*
X1340299Y686243D03*
X1346738Y702492D03*
X1346533Y719898D03*
X1339289Y706461D03*
X1342053Y717339D03*
X1346533Y714780D03*
X1340522Y724133D03*
X1343000Y728458D03*
X1344768Y769675D03*
X1345226Y777675D03*
X1341000Y799000D03*
X1345000Y796000D03*
X1348917D03*
X1352817D03*
X1348000Y832000D03*
X1344000Y825500D03*
X1353000Y824000D03*
X1341500Y831000D03*
X1348275Y849171D03*
X1348170Y880104D03*
X1348134Y896278D03*
X1343500Y911000D03*
X1348500Y913500D03*
X1353948Y943603D03*
X1345948D03*
X1349848Y936755D03*
X1343237Y1241428D03*
X1351876Y1260160D03*
X1341226Y1278592D03*
X1346362Y1278700D03*
X1351673D03*
X1360122Y141247D03*
X1364609Y143518D03*
X1363709Y152373D03*
X1355255Y561032D03*
Y652032D03*
X1367000Y811620D03*
X1365000Y804000D03*
X1355000Y811620D03*
X1360000Y824500D03*
X1369000D03*
X1361500Y831500D03*
X1355000Y829500D03*
X1356141Y910359D03*
X1362510Y912490D03*
X1368155Y912270D03*
X1361000Y904000D03*
X1365948Y939475D03*
X1357948Y938842D03*
X1361948Y943603D03*
X1369948D03*
X1365049Y1028416D03*
X1369765Y1015825D03*
X1365314Y1021793D03*
X1366265Y1039880D03*
X1366289Y1098518D03*
X1369642Y1104335D03*
X1360876Y1260160D03*
X1362308Y1278862D03*
X1367828D03*
X1356856D03*
X1382205Y110784D03*
X1387205D03*
X1386784Y124663D03*
X1376696Y124283D03*
X1381762Y124879D03*
X1386399Y201683D03*
X1381519Y218085D03*
X1386846Y249108D03*
X1383634Y342766D03*
X1384265Y334371D03*
Y352371D03*
X1383963Y366675D03*
X1375108Y420838D03*
X1383343Y508228D03*
X1383907Y516591D03*
X1383556Y554388D03*
X1378415Y558795D03*
Y563984D03*
Y569776D03*
X1378957Y584457D03*
X1382997Y581317D03*
X1383425Y593575D03*
X1378415Y605295D03*
Y610484D03*
Y616276D03*
X1384657Y631620D03*
X1378957Y627988D03*
X1378415Y649795D03*
Y654984D03*
Y660776D03*
X1386289Y672488D03*
X1378957Y675457D03*
X1378415Y696795D03*
Y701984D03*
X1378957Y719488D03*
X1378415Y707776D03*
X1385290Y722400D03*
X1381000Y804000D03*
X1385360Y811757D03*
X1375480Y824745D03*
X1381481Y825415D03*
X1386287Y836500D03*
X1384147Y855177D03*
X1378490Y864853D03*
X1385361Y875675D03*
X1385933Y886594D03*
X1386747Y896548D03*
X1377500Y904000D03*
X1382500Y907500D03*
X1380000Y912500D03*
X1372600Y906458D03*
X1374500Y912000D03*
X1378500Y925500D03*
X1382775Y930281D03*
X1373948Y940103D03*
X1373534Y996755D03*
X1381519Y996280D03*
X1373534Y1012325D03*
X1378938Y1000586D03*
X1374059Y1018860D03*
X1379065Y1019069D03*
X1378559Y1038534D03*
X1384784Y1033783D03*
X1385929Y1038665D03*
X1373874Y1032266D03*
X1385152Y1046591D03*
X1384667Y1223783D03*
X1382078Y1238778D03*
X1380855Y1230148D03*
X1380936Y1270898D03*
X1386122Y1270954D03*
X1373032Y1278566D03*
X1388480Y102249D03*
X1397848Y97667D03*
X1391765Y125107D03*
X1400379Y143762D03*
X1394279Y148717D03*
X1388128Y138838D03*
X1389580Y195176D03*
X1396827Y198733D03*
X1402855Y227824D03*
X1398600Y230556D03*
X1393859Y228646D03*
X1389466Y244571D03*
X1396809Y256394D03*
X1395726Y320529D03*
X1395568Y325529D03*
X1395726Y330529D03*
X1395736Y335529D03*
X1395726Y340529D03*
Y345529D03*
Y360529D03*
Y350529D03*
Y355529D03*
X1391896Y365529D03*
X1399884Y367165D03*
X1389557Y424678D03*
X1390271Y417578D03*
X1403085Y460565D03*
X1397079Y531726D03*
Y544726D03*
X1390741Y561000D03*
Y569000D03*
X1397000Y652000D03*
Y660000D03*
Y699000D03*
Y707000D03*
X1391040Y812027D03*
X1398530Y811717D03*
X1402417Y811692D03*
X1400069Y827515D03*
X1401300Y820485D03*
X1402000Y840000D03*
Y848000D03*
X1389404Y847052D03*
X1402000Y864000D03*
Y876000D03*
Y884000D03*
Y892000D03*
X1391764Y887128D03*
X1402000Y900000D03*
X1387520Y905307D03*
X1387753Y912629D03*
X1394891Y914783D03*
X1402187Y908270D03*
X1396869Y958707D03*
X1402064Y965913D03*
X1389192Y992568D03*
X1394885Y999941D03*
X1392031Y1004375D03*
X1390459Y1017180D03*
X1388128Y1027202D03*
X1402809Y1024184D03*
X1389762Y1043055D03*
X1393909Y1032551D03*
X1399807Y1036155D03*
X1392086Y1092743D03*
X1399748Y1098518D03*
X1403101Y1104335D03*
X1396296Y1270918D03*
X1401428D03*
X1391272Y1270920D03*
X1389052Y1303139D03*
X1406308Y103411D03*
X1406702Y97667D03*
X1417498Y90650D03*
X1403845Y199248D03*
X1407445Y230117D03*
X1408854Y381207D03*
X1408254Y398041D03*
X1407844Y411033D03*
X1415674Y421278D03*
X1417856Y448419D03*
X1410903Y470419D03*
Y461919D03*
X1418903Y461419D03*
X1415623Y492268D03*
X1415823Y482165D03*
X1415064Y500202D03*
X1416413Y495649D03*
X1405992Y534909D03*
X1405619Y541135D03*
X1405685Y546553D03*
X1405708Y552726D03*
X1411622Y610548D03*
X1407566Y622285D03*
X1407754Y616905D03*
X1418439Y633736D03*
X1407952Y633724D03*
X1413432Y633716D03*
X1407835Y627713D03*
X1413452Y641817D03*
X1418000Y696000D03*
Y701000D03*
Y717000D03*
X1410000D03*
X1418000Y724000D03*
Y729000D03*
X1404249Y735858D03*
X1418000Y740000D03*
Y745000D03*
X1407482Y750853D03*
X1418000Y761000D03*
X1406867Y783273D03*
X1409115Y773520D03*
X1414597Y792375D03*
X1406483Y811717D03*
X1413449Y823934D03*
X1405402Y819917D03*
X1405500Y844000D03*
Y836000D03*
Y860000D03*
Y880000D03*
Y868000D03*
X1413500Y876000D03*
X1417797Y879501D03*
X1405500Y888000D03*
Y896000D03*
X1417081D03*
X1413500Y892000D03*
Y884000D03*
X1405500Y904000D03*
X1404760Y915186D03*
X1419337Y942285D03*
X1419446Y977192D03*
X1405090Y981903D03*
X1412698Y997590D03*
X1412609Y1008766D03*
X1412759Y1016266D03*
X1416736Y1242194D03*
X1417711Y1301729D03*
X1409900Y1442356D03*
X1422810Y90615D03*
X1427131Y99961D03*
X1430540Y169454D03*
X1434166Y325361D03*
X1434164Y339232D03*
X1434038Y334114D03*
X1435818Y352361D03*
X1434997Y442603D03*
X1427117Y443071D03*
X1432414Y459371D03*
X1427484Y462004D03*
X1427800Y528578D03*
X1421099Y546830D03*
X1435390Y544895D03*
X1435119Y590801D03*
X1434944Y597130D03*
X1420452Y628078D03*
X1430175Y627852D03*
X1425452Y633473D03*
X1433529Y660564D03*
X1426615Y674112D03*
X1429000Y685000D03*
X1425909Y691120D03*
X1433464Y692658D03*
X1433053Y701839D03*
X1431522Y708633D03*
X1434000Y712958D03*
X1430289Y734961D03*
X1429000Y729000D03*
X1434000Y751958D03*
X1433153Y745839D03*
X1435000Y765500D03*
X1434000Y756958D03*
X1435000Y770500D03*
Y802500D03*
Y814500D03*
Y809500D03*
X1434975Y830500D03*
X1435000Y825500D03*
Y846500D03*
X1427000D03*
X1435043Y874694D03*
X1435082Y869475D03*
X1430217Y880162D03*
X1434858Y887763D03*
X1423190Y905295D03*
X1429907Y936998D03*
X1424897Y936777D03*
X1435516Y936000D03*
X1430839Y965546D03*
X1435229Y1104335D03*
X1420736Y1226194D03*
X1424736Y1238194D03*
X1432736Y1230194D03*
X1421964Y1502813D03*
X1442656Y76899D03*
X1450156D03*
X1436089Y92874D03*
X1451301Y148277D03*
X1438040Y169454D03*
X1451762Y177616D03*
X1446199Y188727D03*
X1443321Y208695D03*
X1442956Y226141D03*
X1436449Y223661D03*
X1451785Y265896D03*
X1446698Y265701D03*
X1448333Y281716D03*
X1449060Y329861D03*
Y320861D03*
X1438829Y329861D03*
X1437064Y320861D03*
X1448500Y340575D03*
X1439712Y336673D03*
X1440420Y346833D03*
X1441180Y354909D03*
X1448572Y349441D03*
X1443041Y363648D03*
X1442633Y371502D03*
X1440523Y382747D03*
X1436930Y461818D03*
X1439462Y529929D03*
X1449393Y566797D03*
X1449993Y578405D03*
X1443775Y596089D03*
X1448994Y596782D03*
X1437770Y628242D03*
X1437738Y686992D03*
X1451976Y693844D03*
X1437533Y704398D03*
Y699280D03*
X1438930Y716363D03*
X1446860Y730735D03*
X1437738Y730992D03*
X1437533Y743280D03*
Y748398D03*
X1447289Y776461D03*
X1446000Y770500D03*
X1451000Y793458D03*
Y798458D03*
X1450253Y787339D03*
X1447000Y810500D03*
Y818500D03*
X1448000Y834500D03*
X1449000Y844500D03*
X1448581Y924436D03*
X1448743Y935588D03*
X1441088Y976409D03*
X1440700Y981763D03*
X1440869Y1010256D03*
X1447361Y1273222D03*
X1457347Y31518D03*
X1457829Y26425D03*
X1461905Y100625D03*
X1454924Y97475D03*
X1462484Y141247D03*
X1466971Y143518D03*
X1453921Y143740D03*
X1466071Y152373D03*
X1452343Y172190D03*
X1464158Y192490D03*
X1456801Y266114D03*
X1461160Y281307D03*
X1454274Y281982D03*
X1455079Y290755D03*
X1463145Y391579D03*
X1456958Y556317D03*
X1459146Y565573D03*
X1455419Y578986D03*
X1454944Y596729D03*
X1461474Y655807D03*
X1468372Y673812D03*
X1454504Y777575D03*
X1454533Y784780D03*
X1454738Y772492D03*
X1454533Y789898D03*
X1453102Y821102D03*
X1454541Y831339D03*
X1453102Y826500D03*
X1452619Y836457D03*
X1457174Y874859D03*
X1461113Y871389D03*
X1462391Y892822D03*
X1462500Y905295D03*
X1467508Y905405D03*
X1458202Y960288D03*
X1457937Y966712D03*
X1467096Y988813D03*
X1458892Y1007522D03*
X1465658Y1006648D03*
X1463025Y1018307D03*
X1459267Y1013678D03*
X1456280Y1023405D03*
X1459683Y1028377D03*
X1452784Y1289102D03*
X1457794Y1292726D03*
X1474746Y60513D03*
X1474874Y85731D03*
X1483287Y86012D03*
X1479380Y94279D03*
X1470567Y103621D03*
X1484567Y110784D03*
X1479058Y124283D03*
X1484124Y124879D03*
X1469913Y183834D03*
X1470023Y178560D03*
X1470086Y172665D03*
X1469433Y190185D03*
X1478800Y196665D03*
X1470203Y200864D03*
X1470292Y212455D03*
X1470226Y207037D03*
X1475101Y228631D03*
X1475264Y680933D03*
X1476716Y704398D03*
X1479500Y689630D03*
Y697630D03*
X1479759Y720885D03*
X1469957Y706957D03*
X1479794Y709388D03*
X1472000Y727500D03*
X1480000Y731500D03*
X1476716Y748398D03*
X1480000Y739500D03*
X1471006Y744818D03*
X1470801Y739280D03*
X1479665Y754555D03*
X1474883Y868206D03*
X1473387Y897425D03*
X1482195Y885807D03*
X1472000Y929500D03*
X1472500Y935324D03*
X1480144Y946880D03*
X1480414Y952214D03*
X1479196Y970000D03*
X1480414Y975064D03*
X1475096Y988813D03*
X1483096D03*
X1482535Y1024254D03*
X1471854Y1035088D03*
X1474384Y1165091D03*
X1480675Y1202103D03*
X1483308Y1214372D03*
X1479063Y1218169D03*
X1489556Y17645D03*
X1489829Y29424D03*
X1490563Y23043D03*
X1490842Y102249D03*
X1500210Y97667D03*
X1489567Y110784D03*
X1494127Y125107D03*
X1489146Y124663D03*
X1496641Y148717D03*
X1490490Y138838D03*
X1491942Y195176D03*
X1499189Y198733D03*
X1488761Y201683D03*
X1496221Y228646D03*
X1491828Y244571D03*
X1489208Y249108D03*
X1499171Y256394D03*
X1486860Y327200D03*
X1500659Y330024D03*
X1495605Y322700D03*
X1487318Y318200D03*
X1500386Y344642D03*
X1486913Y340327D03*
X1495689Y332534D03*
X1495521Y340700D03*
Y349681D03*
X1495925Y358700D03*
X1499839Y354001D03*
X1486890Y368576D03*
X1488799Y547918D03*
X1488731Y739500D03*
X1496629Y765000D03*
X1493301Y776911D03*
X1496814Y773000D03*
X1497000Y781000D03*
X1499633Y787794D03*
X1493716Y789898D03*
X1495170Y796670D03*
X1487050Y809413D03*
X1496845Y809000D03*
X1496806Y817000D03*
X1486386Y825296D03*
X1493038Y833898D03*
X1495240Y825000D03*
X1500563Y881339D03*
X1500063Y870339D03*
X1494954Y895264D03*
X1500417Y915191D03*
X1484824Y927324D03*
X1490000Y928655D03*
X1485500Y932500D03*
X1498983Y944443D03*
X1495500Y972500D03*
X1489500D03*
X1491096Y988813D03*
X1499096D03*
X1490235Y1004816D03*
X1487266Y1002046D03*
X1495339Y1021954D03*
X1486030Y1016827D03*
X1491877D03*
X1496185Y1102091D03*
Y1114691D03*
Y1127291D03*
Y1139891D03*
Y1152491D03*
Y1165091D03*
Y1177691D03*
X1489793Y1207737D03*
X1497693Y1230407D03*
X1508670Y103411D03*
X1509064Y97667D03*
X1502741Y143762D03*
X1506207Y199248D03*
X1509807Y230117D03*
X1500962Y230556D03*
X1505217Y227824D03*
X1501000Y317500D03*
X1501684Y336561D03*
X1516838Y347422D03*
X1515909Y354601D03*
X1516636Y458711D03*
X1511691Y546805D03*
X1502158Y899479D03*
X1504208Y909740D03*
X1506151Y915726D03*
X1509274Y921226D03*
X1516139Y918399D03*
X1511256Y916334D03*
X1509500Y937000D03*
Y944138D03*
X1516500Y947500D03*
X1504085Y943714D03*
X1501812Y938397D03*
X1509500Y950500D03*
X1507096Y988813D03*
X1515096D03*
X1513286Y1012354D03*
X1507831Y1009354D03*
X1513286Y1024954D03*
X1507831Y1021954D03*
X1501640Y1105091D03*
Y1117691D03*
Y1130291D03*
Y1142891D03*
Y1155491D03*
Y1168091D03*
Y1180691D03*
X1507232Y1214967D03*
X1508356Y1220068D03*
X1511550Y1224260D03*
X1506807Y1234921D03*
X1507058Y1229402D03*
X1525172Y90615D03*
X1519860Y90650D03*
X1529493Y99961D03*
X1532902Y169454D03*
X1519321Y378600D03*
X1532975Y546062D03*
X1519185Y615600D03*
X1520729Y634190D03*
X1529000Y884006D03*
X1525022Y909558D03*
X1526206Y918341D03*
X1521500Y947500D03*
X1528500Y947612D03*
X1529097Y967090D03*
X1517470Y967471D03*
X1531096Y988813D03*
X1523096D03*
X1527096Y997860D03*
X1526810Y1025090D03*
X1522904Y1021256D03*
X1521939Y1040818D03*
X1522099Y1035521D03*
X1531993Y1056453D03*
X1531961Y1050849D03*
X1524953Y1051037D03*
X1527559Y1143390D03*
X1545018Y76899D03*
X1538451Y92874D03*
X1540402Y169454D03*
X1548561Y188727D03*
X1545683Y208695D03*
X1538811Y223661D03*
X1545318Y226141D03*
X1549060Y265701D03*
X1545583Y316363D03*
X1539140Y320863D03*
X1545636Y325363D03*
X1542797Y329863D03*
X1545846Y334363D03*
X1544951Y343363D03*
X1545434Y352363D03*
X1548080Y910757D03*
X1547644Y903060D03*
X1546224Y1142520D03*
X1536909Y1151870D03*
X1538767Y1146271D03*
X1536909Y1159350D03*
X1540649Y1155610D03*
X1538845Y1168638D03*
X1540487Y1163381D03*
X1552518Y76899D03*
X1564267Y100625D03*
X1557286Y97475D03*
X1564846Y141247D03*
X1556283Y143740D03*
X1553663Y148277D03*
X1554705Y172190D03*
X1554124Y177616D03*
X1559163Y266114D03*
X1554147Y265896D03*
X1563522Y281307D03*
X1556636Y281982D03*
X1550695Y281716D03*
X1557441Y290755D03*
X1550931Y305158D03*
X1553534Y327337D03*
X1553597Y336601D03*
X1551175Y347283D03*
X1556588Y545528D03*
X1564670Y650122D03*
X1565132Y668153D03*
Y677843D03*
X1557444Y1135040D03*
X1553738Y1194917D03*
X1564960Y1217322D03*
X1577108Y60513D03*
X1577236Y85731D03*
X1581742Y94279D03*
X1572929Y103621D03*
X1581420Y124283D03*
X1569333Y143518D03*
X1568433Y152373D03*
X1572275Y183834D03*
X1572385Y178560D03*
X1572448Y172665D03*
X1571795Y190185D03*
X1566520Y192490D03*
X1572565Y200864D03*
X1572654Y212455D03*
X1572588Y207037D03*
X1581194Y208864D03*
X1577463Y228631D03*
X1578420Y338309D03*
X1574775Y344127D03*
X1575935Y382109D03*
X1577862Y554121D03*
X1570200Y551040D03*
X1579760Y595500D03*
X1574760Y606929D03*
X1579260Y604567D03*
X1574720Y618400D03*
X1575001Y612592D03*
X1580418Y610072D03*
X1580354Y616317D03*
X1577077Y631712D03*
X1571888Y649380D03*
X1576181Y1217322D03*
X1585649Y86012D03*
X1593204Y102249D03*
X1586929Y110784D03*
X1591929D03*
X1596489Y125107D03*
X1586486Y124879D03*
X1591508Y124663D03*
X1592852Y138838D03*
X1594304Y195176D03*
X1591123Y201683D03*
X1594190Y244571D03*
X1591570Y249108D03*
X1595069Y337361D03*
X1595109Y342663D03*
X1594466Y350984D03*
X1586760Y544000D03*
X1594760Y568000D03*
X1595429Y1055975D03*
X1596261Y1062847D03*
X1583661Y1217322D03*
Y1209842D03*
X1587401Y1213582D03*
X1596790Y1442557D03*
X1596038Y1492000D03*
X1590748Y1523377D03*
X1602572Y97667D03*
X1611032Y103411D03*
X1611426Y97667D03*
X1605103Y143762D03*
X1599003Y148717D03*
X1608569Y199248D03*
X1601551Y198733D03*
X1603324Y230556D03*
X1607579Y227824D03*
X1612169Y230117D03*
X1598583Y228646D03*
X1604677Y253198D03*
X1599527Y404718D03*
Y412718D03*
X1600262Y479577D03*
X1614338Y636842D03*
X1606190Y803774D03*
X1606709Y819165D03*
X1604258Y1058763D03*
X1601581Y1050045D03*
X1611857Y1053324D03*
X1600008Y1488492D03*
X1601500Y1514500D03*
X1608500Y1506000D03*
X1613790Y1531334D03*
X1609348Y1527334D03*
X1613790Y1523334D03*
X1604000Y1519000D03*
X1600732Y1539334D03*
X1609348Y1535334D03*
X1622222Y90650D03*
X1627534Y90615D03*
X1617595Y399648D03*
X1630650Y443035D03*
X1623955Y442956D03*
X1629259Y433003D03*
X1620385Y465874D03*
X1618538Y618288D03*
X1617843Y665140D03*
X1621425Y1055787D03*
X1646707Y76900D03*
X1640813Y92874D03*
X1631855Y99961D03*
X1635264Y169454D03*
X1642764D03*
X1641173Y223661D03*
X1636271Y403307D03*
X1632439Y452265D03*
X1633225Y458455D03*
X1635185Y446595D03*
X1644552Y871353D03*
X1635176Y886761D03*
X1644718Y909263D03*
X1635000Y919263D03*
X1644325Y942120D03*
X1637771Y952120D03*
X1636993Y1064608D03*
X1640581Y1551907D03*
X1654207Y76900D03*
X1659648Y97475D03*
X1658645Y143740D03*
X1656025Y148277D03*
X1656486Y177616D03*
X1657067Y172190D03*
X1650923Y188727D03*
X1648045Y208695D03*
X1647680Y226141D03*
X1656509Y265896D03*
X1661525Y266114D03*
X1651422Y265701D03*
X1653057Y281716D03*
X1658998Y281982D03*
X1659803Y290755D03*
X1649061Y336546D03*
X1659760Y388000D03*
X1650044Y435158D03*
X1649789Y440489D03*
X1653490Y458572D03*
X1647402Y881460D03*
X1647565Y981432D03*
X1662204Y1112598D03*
X1657400Y1128100D03*
X1662204Y1142519D03*
X1658464Y1149999D03*
X1648730Y1163114D03*
X1679470Y60513D03*
X1679598Y85731D03*
X1675291Y103621D03*
X1666629Y100625D03*
X1667208Y141247D03*
X1671695Y143518D03*
X1670795Y152373D03*
X1674637Y183834D03*
X1674810Y172665D03*
X1674747Y178560D03*
X1674157Y190185D03*
X1668882Y192490D03*
X1674927Y200864D03*
X1674950Y207037D03*
X1675016Y212455D03*
X1664082Y231021D03*
X1665884Y281307D03*
X1668979Y339559D03*
X1670260Y377912D03*
X1669260Y391496D03*
X1663618Y393858D03*
X1666959Y382047D03*
X1670260Y386500D03*
X1669260Y409000D03*
X1665260Y398583D03*
X1670348Y397912D03*
X1667260Y403500D03*
X1667815Y1064640D03*
X1667272Y1185514D03*
X1667710Y1178467D03*
X1688011Y86012D03*
X1695566Y102249D03*
X1684104Y94279D03*
X1694291Y110784D03*
X1689291D03*
X1683782Y124283D03*
X1693870Y124663D03*
X1688848Y124879D03*
X1695214Y138838D03*
X1693485Y201683D03*
X1683556Y208864D03*
X1679825Y228631D03*
X1693932Y249108D03*
X1686339Y314890D03*
X1683523Y324518D03*
X1687424Y347937D03*
X1692676Y348015D03*
X1691182Y357016D03*
X1680905Y1142519D03*
X1704934Y97667D03*
X1698851Y125107D03*
X1707465Y143762D03*
X1701365Y148717D03*
X1696666Y195176D03*
X1710931Y199248D03*
X1703913Y198733D03*
X1705686Y230556D03*
X1709941Y228747D03*
X1700945Y228646D03*
X1696552Y244571D03*
X1703895Y256394D03*
X1699205Y368854D03*
X1699391Y433834D03*
X1704945Y442080D03*
X1698716Y550065D03*
X1711333Y1146609D03*
X1706450Y1173065D03*
X1704760Y1202200D03*
X1706159Y1224512D03*
X1702500Y1221062D03*
X1702275Y1232283D03*
X1709144Y1233951D03*
X1713394Y103411D03*
X1713788Y97667D03*
X1724584Y90650D03*
X1714531Y230117D03*
X1720571Y385644D03*
X1725746Y385123D03*
X1718318Y399918D03*
X1725154Y406060D03*
X1717905Y418996D03*
X1717650Y431730D03*
X1724627Y459330D03*
X1724580Y454214D03*
X1724923Y449045D03*
X1723805Y1142666D03*
X1725680Y1157544D03*
X1724191Y1167768D03*
X1713239Y1176038D03*
X1728343Y1185205D03*
X1719692Y1187215D03*
X1719385Y1180175D03*
X1712715Y1188500D03*
X1717406Y1195603D03*
X1715324Y1203115D03*
X1716567Y1221197D03*
X1714435Y1237535D03*
X1726578Y1228760D03*
X1712966Y1229841D03*
X1743175Y92874D03*
X1729896Y90615D03*
X1734217Y99961D03*
X1737626Y169454D03*
X1743535Y223661D03*
X1744524Y379429D03*
X1730746Y385123D03*
X1737746D03*
X1741420Y391569D03*
X1739847Y409016D03*
X1738824Y456034D03*
Y461034D03*
X1739917Y1146937D03*
X1732137Y1157404D03*
X1729210Y1167768D03*
X1733052Y1187310D03*
X1737689Y1185238D03*
X1737482Y1180235D03*
X1730457Y1197626D03*
X1731619Y1210089D03*
X1750752Y82285D03*
X1758252D03*
X1745126Y169454D03*
X1758848Y177616D03*
X1759429Y172190D03*
X1753285Y188727D03*
X1750407Y208695D03*
X1750042Y226141D03*
X1753784Y265701D03*
X1758871Y265896D03*
X1755419Y281716D03*
X1752497Y371076D03*
X1750135Y379088D03*
X1755433Y379028D03*
X1750187Y406739D03*
X1756894Y472020D03*
X1756553Y466409D03*
X1756954Y477318D03*
X1756391Y487382D03*
X1745824Y987058D03*
X1759569Y1021944D03*
X1759947Y1599029D03*
X1750685Y1618504D03*
X1762010Y97475D03*
X1768991Y100625D03*
X1776999Y183834D03*
X1771244Y192490D03*
X1776519Y190185D03*
X1763887Y266114D03*
X1768246Y281307D03*
X1761360Y281982D03*
X1762165Y290755D03*
X1765497Y379591D03*
X1767633Y407104D03*
X1765093Y423944D03*
X1765153Y413611D03*
X1764906Y474382D03*
X1776561Y467560D03*
X1777061Y475560D03*
X1768844Y1023694D03*
X1772188Y1428369D03*
X1766313Y1580198D03*
X1761072Y1590719D03*
X1765040Y1599511D03*
X1764422Y1640303D03*
X1762041Y1631511D03*
X1768422Y1632245D03*
X1773820Y1631238D03*
X1781832Y60513D03*
X1781960Y85731D03*
X1790712Y81713D03*
X1786466Y94279D03*
X1777172Y172665D03*
X1777109Y178560D03*
X1777289Y200864D03*
X1777378Y212455D03*
X1777312Y207037D03*
X1785918Y208864D03*
X1781559Y219379D03*
X1782187Y228631D03*
X1786170Y448931D03*
X1792527Y452799D03*
X1790061Y474513D03*
X1779404Y826570D03*
X1781263Y964660D03*
X1786863Y985060D03*
X1779033Y1023432D03*
X1792613Y1079394D03*
X1781559Y1082075D03*
X1783278Y1208140D03*
X1791099Y1260421D03*
X1787745Y1437765D03*
X1777131Y1604357D03*
X1809095Y435101D03*
X1803700Y440101D03*
X1803530Y431112D03*
X1809358Y442114D03*
X1803335Y452718D03*
X1809346Y452601D03*
X1797907Y452987D03*
X1809338Y447121D03*
X1802363Y989660D03*
X1801961Y1081717D03*
X1795819Y1088553D03*
X1796990Y1134564D03*
X1797924Y1148330D03*
X1796607Y1200108D03*
X1806835Y1214668D03*
X1800489Y1220598D03*
X1807243Y1219955D03*
X1802670Y1210905D03*
X1805126Y1225745D03*
X1795374Y1444543D03*
X1802813Y1464015D03*
X1817439Y447101D03*
X1816756Y1089145D03*
Y1094145D03*
X1816235Y1083970D03*
X1810346Y1082250D03*
X1816756Y1101145D03*
X1810310Y1104819D03*
X1812130Y1205349D03*
X1814741Y1217093D03*
X1812202Y1432624D03*
G54D20*
X19859Y1520657D03*
X18879Y1534334D03*
X69049Y847718D03*
X281594Y1211712D03*
X270374Y1215452D03*
X336755Y1143489D03*
X341266Y1171956D03*
X415015Y1088205D03*
X418495Y1106867D03*
X422665Y1325323D03*
X426665D03*
X423200Y1397500D03*
X430878Y1081816D03*
X431114Y1272701D03*
X450623Y1106867D03*
X484082D03*
X513324Y693892D03*
X515357Y698253D03*
X511359Y698494D03*
X510654Y703806D03*
X523299Y709313D03*
X519072Y709183D03*
X516210Y1106867D03*
X518576Y1273004D03*
X525712Y1272992D03*
X793842Y1143384D03*
X798353Y1172011D03*
X814080Y864464D03*
X834465Y884538D03*
X847098Y891213D03*
X897636Y839406D03*
X889336Y1452554D03*
X889244Y1468859D03*
X903817Y879770D03*
X919038Y579378D03*
X929557Y889258D03*
X917744Y1453573D03*
X959545Y918306D03*
X1184547Y1215452D03*
X1250928Y1142828D03*
X1255439Y1172008D03*
X1253904Y1519645D03*
X1323205Y867665D03*
X1329189Y1088205D03*
X1332669Y1106867D03*
X1324886Y1278962D03*
X1364797Y1106867D03*
X1375193Y811724D03*
X1379858Y1420701D03*
X1398256Y1106867D03*
X1409066Y1272899D03*
X1405066D03*
X1413066D03*
X1430384Y1106867D03*
X1439031Y957683D03*
X1443769Y1562173D03*
X1468869Y1018469D03*
X1598574Y1543373D03*
X1641634Y1215452D03*
X1708015Y1142700D03*
X1712526Y1171950D03*
X1809078Y2165771D03*
X1806706Y2180760D03*
X1812366Y2063809D03*
X1822066Y2054109D03*
X1812366D03*
X1813087Y2087512D03*
X1825427Y2104853D03*
X1817378Y2165771D03*
X1815006Y2180760D03*
X1841295Y2065122D03*
X1832995D03*
X1833649Y2057507D03*
X1830872Y2083503D03*
X1840875Y2083215D03*
X1837649Y2072324D03*
X1829349D03*
X1833727Y2104853D03*
X1835862Y2121040D03*
X1833506Y2185252D03*
X1852032Y2052576D03*
X1854559Y2077931D03*
X1851762Y2121040D03*
X1854796Y2170548D03*
X1846496D03*
X1855978Y2185118D03*
X1847678D03*
X1859032Y2052576D03*
X1870505Y2064156D03*
X1860338Y2071384D03*
X1874505Y2078973D03*
X1860234Y2157701D03*
X1867072Y2174962D03*
X1864547Y2185020D03*
X1890039Y2066092D03*
X1878805Y2064156D03*
X1886128Y2075919D03*
X1882805Y2078973D03*
X1876497Y2070684D03*
X1884535Y2155415D03*
X1882972Y2174962D03*
X1882111Y2179074D03*
X1874932Y2180585D03*
X1881852Y2196600D03*
X1886699Y2183170D03*
X1876697D03*
X1905939Y2066092D03*
X1893118Y2054585D03*
X1905944Y2055424D03*
X1898342Y2062143D03*
X1901295Y2072745D03*
X1892835Y2155415D03*
X1902872Y2178531D03*
X1894572D03*
X1893087Y2168011D03*
X1896403Y2185019D03*
X1917195Y2072745D03*
X1917550Y2158451D03*
X1909250D03*
X1922010Y2151829D03*
X1913710D03*
X1921855Y2172152D03*
X1936295Y2074343D03*
X1935195Y2155918D03*
X1936377Y2163810D03*
X1924735Y2178131D03*
X1936212Y2173508D03*
X1930155Y2172152D03*
X1931738Y2182647D03*
X1923438D03*
X1941040Y2070124D03*
X1951095Y2155918D03*
X1946077Y2163810D03*
X1969128Y2161283D03*
X1959428D03*
X1969128Y2151583D03*
X1959428D03*
G54D12*
X15916Y1041679D03*
X28318D03*
X50051Y1041371D03*
X37649D03*
X438119Y1234726D03*
X450521D03*
X476828D03*
X489230D03*
X862606Y1050682D03*
X875008D03*
X896741Y1050374D03*
X884339D03*
X926583Y1050682D03*
X938985D03*
X960718Y1050374D03*
X948316D03*
X1352293Y1234726D03*
X1364695D03*
X1391002D03*
X1403404D03*
X1770563Y1051168D03*
X1782965D03*
X1804698Y1050860D03*
X1792296D03*
G54D21*
X34946Y1082645D03*
X35992Y1090694D03*
X33892D03*
X35936Y1093825D03*
X33836D03*
X42947Y1073034D03*
X40847D03*
X37046Y1082645D03*
X97906Y1021028D03*
X100006D03*
X97837Y1024139D03*
X99937D03*
X181618Y562188D03*
X179518D03*
X181618Y565388D03*
X179518D03*
X181618Y568588D03*
X179518D03*
X181618Y571988D03*
X179518D03*
X181618Y575388D03*
X179518D03*
X181430Y1144389D03*
X181450Y1151870D03*
Y1155610D03*
X173949Y1153740D03*
X176049D03*
X173949Y1149999D03*
X176049D03*
X181450Y1166830D03*
X173949Y1157480D03*
X176049D03*
X181450Y1159350D03*
Y1162450D03*
Y1170570D03*
X173949Y1161220D03*
X176049D03*
X173949Y1164960D03*
X176049D03*
X173949Y1174310D03*
X176049D03*
X181450Y1181800D03*
Y1178000D03*
X173949Y1178051D03*
X176049D03*
X173949Y1181791D03*
X176049D03*
X181450Y1185200D03*
X194750Y1136909D03*
X192650D03*
X194750Y1144389D03*
X192650D03*
X182950Y1148129D03*
X185050D03*
X194750Y1151869D03*
X192650D03*
Y1148129D03*
X194750D03*
X183530Y1144389D03*
X183550Y1151870D03*
Y1155610D03*
Y1166830D03*
X192830D03*
X194930D03*
X183550Y1159350D03*
Y1162450D03*
Y1170570D03*
X194550Y1185100D03*
X192450D03*
X182950Y1174310D03*
X185050D03*
X194750Y1178250D03*
X192650D03*
Y1181791D03*
X194750D03*
X183550Y1181800D03*
Y1178000D03*
Y1185200D03*
X195570Y1193011D03*
X193470D03*
X188090D03*
X190190D03*
X200311Y1166830D03*
X202411D03*
X207791D03*
X209891D03*
X230132D03*
X222752D03*
X224852D03*
X215271D03*
X217371D03*
X239050Y1166900D03*
X236950D03*
X241950D03*
X244050D03*
X232232Y1166830D03*
X248833D03*
X250933D03*
X256313D03*
X258413D03*
X270373Y1129429D03*
X272473D03*
X277034Y1140649D03*
X274934D03*
X277034Y1136909D03*
X274934D03*
X270373Y1133169D03*
X272473D03*
X277034Y1144389D03*
X274934D03*
X269553Y1155610D03*
X267453D03*
X278674D03*
X263713Y1166830D03*
X265813D03*
X278674Y1159350D03*
X273294D03*
X271194D03*
X273294Y1166830D03*
X271194D03*
X273294Y1170570D03*
X271194D03*
X278674Y1166830D03*
Y1170570D03*
X270373Y1178051D03*
X268273D03*
X271194Y1185531D03*
X273294D03*
X277854Y1181791D03*
X273294D03*
X271194D03*
X278674Y1174310D03*
X269553D03*
X267453D03*
X271194Y1189271D03*
X273294D03*
X271194Y1193011D03*
X273294D03*
X287927Y436924D03*
X290027D03*
X287927Y433524D03*
X290027D03*
X287927Y430124D03*
X290027D03*
X287927Y440124D03*
X290027D03*
X287927Y443324D03*
X290027D03*
X280774Y1155610D03*
X288254Y1157480D03*
X286154D03*
X288254Y1161220D03*
X286154D03*
X288254Y1168700D03*
X286154D03*
X288254Y1172440D03*
X286154D03*
X288254Y1164960D03*
X286154D03*
X280774Y1159350D03*
Y1166830D03*
Y1170570D03*
X279954Y1181791D03*
X285334D03*
X283234D03*
X280774Y1174310D03*
X460846Y1250700D03*
X458746D03*
X460846Y1254104D03*
X458746D03*
X460846Y1247512D03*
X458746D03*
X460846Y1244163D03*
X458746D03*
X465316Y1247512D03*
X467416D03*
X465316Y1254104D03*
X467416D03*
X465316Y1244109D03*
X467416D03*
X465316Y1250814D03*
X467416D03*
X636604Y562188D03*
Y565388D03*
Y568588D03*
Y571988D03*
Y575388D03*
X631036Y1149999D03*
X633136D03*
X631036Y1153740D03*
X633136D03*
X631036Y1157480D03*
X633136D03*
X631036Y1172500D03*
X633136D03*
X631036Y1161220D03*
X633136D03*
X631036Y1164960D03*
X633136D03*
X631036Y1179921D03*
X633136D03*
X631036Y1176180D03*
X633136D03*
X638704Y562188D03*
Y565388D03*
Y568588D03*
Y571988D03*
Y575388D03*
X651837Y1136909D03*
X649737D03*
X651837Y1144389D03*
X649737D03*
X651837Y1151869D03*
X649737D03*
Y1148129D03*
X651837D03*
X640037D03*
X642137D03*
X638517Y1144389D03*
X640617D03*
X638500Y1151870D03*
X640600D03*
X638500Y1155610D03*
X640600D03*
X638500Y1166830D03*
X640600D03*
X649817D03*
X651917D03*
X638500Y1159350D03*
X640600D03*
X638500Y1162500D03*
X640600D03*
X638500Y1170570D03*
X640600D03*
X651837Y1178250D03*
X649737D03*
Y1181791D03*
X651837D03*
X651637Y1185100D03*
X649537D03*
X639850Y1174900D03*
X641950D03*
X638500Y1185342D03*
X640600D03*
X638537Y1181800D03*
X640637D03*
X638537Y1178000D03*
X640637D03*
X645177Y1193011D03*
X647277D03*
X652657D03*
X650557D03*
X657298Y1166830D03*
X659398D03*
X664778D03*
X666878D03*
X672258D03*
X674358D03*
X679739D03*
X681839D03*
X687219D03*
X689319D03*
X699179D03*
X701279D03*
X695899D03*
X693799D03*
X713400D03*
X715500D03*
X705920D03*
X708020D03*
X727460Y1133169D03*
X729560D03*
X727460Y1129429D03*
X729560D03*
X734121Y1136909D03*
X732021D03*
X734121Y1140649D03*
X732021D03*
X734121Y1144389D03*
X732021D03*
X726640Y1155610D03*
X724540D03*
X730381Y1159350D03*
X728281D03*
X730450Y1162800D03*
X728350D03*
X730381Y1166830D03*
X728281D03*
X720800D03*
X722900D03*
X730381Y1170570D03*
X728281D03*
Y1189271D03*
X730381D03*
X728281Y1185531D03*
X730381D03*
Y1181791D03*
X728281D03*
X726640Y1174310D03*
X724540D03*
X728281Y1193011D03*
X730381D03*
X745013Y440124D03*
X747113D03*
X745013Y430124D03*
X747113D03*
X745013Y433524D03*
X747113D03*
X745013Y436924D03*
X747113D03*
X745013Y443324D03*
X747113D03*
X737861Y1155610D03*
X735761D03*
X745341Y1164960D03*
X743241D03*
X745341Y1161220D03*
X743241D03*
X745341Y1168700D03*
X743241D03*
X745341Y1172440D03*
X743241D03*
X737861Y1159350D03*
X735761D03*
X737861Y1170570D03*
X735761D03*
X737861Y1166830D03*
X735761D03*
X745341Y1157480D03*
X743241D03*
X737861Y1174310D03*
X735761D03*
X734941Y1181791D03*
X737041D03*
X742421D03*
X740321D03*
X883265Y1100705D03*
X881165D03*
X910013Y1008536D03*
X912113D03*
X909959Y1011750D03*
X912059D03*
X921107Y1090015D03*
X923207D03*
X1088122Y1153740D03*
X1090222D03*
X1088122Y1149999D03*
X1090222D03*
X1088122Y1164960D03*
X1090222D03*
X1088122Y1161220D03*
X1090222D03*
X1088122Y1157480D03*
X1090222D03*
X1088122Y1181791D03*
X1090222D03*
X1088122Y1178051D03*
X1090222D03*
X1088122Y1174310D03*
X1090222D03*
X1095791Y568588D03*
X1093691D03*
X1095791Y565388D03*
X1093691D03*
X1095791Y562188D03*
X1093691D03*
X1095791Y571988D03*
X1093691D03*
X1095791Y575388D03*
X1093691D03*
X1106823Y1136909D03*
Y1151869D03*
Y1148129D03*
Y1144389D03*
X1095623Y1155610D03*
X1097723D03*
X1095623Y1151870D03*
X1097723D03*
X1095603Y1142579D03*
X1097703D03*
X1097123Y1148129D03*
X1099223D03*
X1107003Y1166830D03*
X1095623Y1170570D03*
X1097723D03*
X1095623Y1166830D03*
X1097723D03*
X1095623Y1162450D03*
X1097723D03*
X1095623Y1159350D03*
X1097723D03*
X1106623Y1185100D03*
X1106823Y1181791D03*
Y1178250D03*
X1095623Y1185200D03*
X1097723D03*
X1095623Y1181800D03*
X1097723D03*
X1095623Y1178000D03*
X1097723D03*
X1097123Y1174310D03*
X1099223D03*
X1107643Y1193011D03*
X1102263D03*
X1104363D03*
X1108923Y1136909D03*
Y1151869D03*
Y1148129D03*
Y1144389D03*
X1121964Y1166830D03*
X1124064D03*
X1114484D03*
X1116584D03*
X1109103D03*
X1108723Y1185100D03*
X1108923Y1181791D03*
Y1178250D03*
X1109743Y1193011D03*
X1136925Y1166830D03*
X1139025D03*
X1129444D03*
X1131544D03*
X1156123Y1166900D03*
X1153223D03*
X1151123D03*
X1144305Y1166830D03*
X1146405D03*
X1170486D03*
X1172586D03*
X1163006D03*
X1165106D03*
X1158223Y1166900D03*
X1189107Y1140649D03*
Y1136909D03*
X1184546Y1133169D03*
X1186646D03*
X1184546Y1129429D03*
X1186646D03*
X1189107Y1144389D03*
X1183726Y1155610D03*
X1181626D03*
X1187467Y1170570D03*
X1185367D03*
X1187467Y1166830D03*
X1185367D03*
X1187467Y1159350D03*
X1185367D03*
X1177886Y1166830D03*
X1179986D03*
X1185367Y1189271D03*
X1187467D03*
X1185367Y1185531D03*
X1187467D03*
Y1181791D03*
X1185367D03*
X1184546Y1178051D03*
X1182446D03*
X1183726Y1174310D03*
X1181626D03*
X1185367Y1193011D03*
X1187467D03*
X1202100Y433524D03*
X1204200D03*
X1202100Y430124D03*
X1204200D03*
X1202100Y440124D03*
X1204200D03*
X1202100Y436924D03*
X1204200D03*
X1202100Y443324D03*
X1204200D03*
X1191207Y1140649D03*
Y1136909D03*
X1194947Y1155610D03*
X1192847D03*
X1191207Y1144389D03*
X1202427Y1172440D03*
X1200327D03*
X1202427Y1168700D03*
X1200327D03*
X1202427Y1164960D03*
X1200327D03*
X1202427Y1161220D03*
X1200327D03*
X1202427Y1157480D03*
X1200327D03*
X1194947Y1170570D03*
X1192847D03*
X1194947Y1166830D03*
X1192847D03*
X1194947Y1159350D03*
X1192847D03*
X1194947Y1174310D03*
X1192847D03*
X1192027Y1181791D03*
X1194127D03*
X1199507D03*
X1197407D03*
X1375020Y1254104D03*
X1372920D03*
X1375020Y1247512D03*
X1372920D03*
X1375020Y1250700D03*
X1372920D03*
X1379490Y1254104D03*
X1381590D03*
X1379490Y1247512D03*
X1381590D03*
X1379490Y1250814D03*
X1381590D03*
X1379490Y1244109D03*
X1381590D03*
X1545209Y1149999D03*
Y1153740D03*
Y1157480D03*
Y1161220D03*
Y1164960D03*
Y1174310D03*
Y1178051D03*
Y1181791D03*
X1552878Y568588D03*
X1550778D03*
X1552878Y565388D03*
X1550778D03*
X1552878Y562188D03*
X1550778D03*
X1552878Y571988D03*
X1550778D03*
X1552878Y575388D03*
X1550778D03*
X1552690Y1144389D03*
X1554790D03*
X1554210Y1148129D03*
X1556310D03*
X1552710Y1155610D03*
X1554810D03*
X1552710Y1151870D03*
X1554810D03*
X1547309Y1149999D03*
Y1153740D03*
X1552710Y1170570D03*
X1554810D03*
X1552710Y1166830D03*
X1554810D03*
X1552710Y1162450D03*
X1554810D03*
X1552710Y1159350D03*
X1554810D03*
X1547309Y1157480D03*
Y1161220D03*
Y1164960D03*
X1552710Y1185200D03*
X1554810D03*
X1552710Y1181800D03*
X1554810D03*
X1552710Y1178000D03*
X1554810D03*
X1554210Y1174310D03*
X1556310D03*
X1547309D03*
Y1178051D03*
Y1181791D03*
X1559350Y1193011D03*
X1561450D03*
X1566010Y1136909D03*
X1563910D03*
X1566010Y1144389D03*
X1563910D03*
Y1148129D03*
X1566010D03*
Y1151869D03*
X1563910D03*
X1564090Y1166830D03*
X1566190D03*
X1571571D03*
X1573671D03*
X1579051D03*
X1566010Y1178250D03*
X1563910D03*
Y1181791D03*
X1566010D03*
X1565810Y1185100D03*
X1563710D03*
X1566830Y1193011D03*
X1564730D03*
X1586531Y1166830D03*
X1588631D03*
X1594012D03*
X1581151D03*
X1601392D03*
X1603492D03*
X1610310Y1166900D03*
X1608210D03*
X1596112Y1166830D03*
X1613210Y1166900D03*
X1615310D03*
X1620093Y1166830D03*
X1622193D03*
X1627573D03*
X1641633Y1129429D03*
X1643733D03*
X1641633Y1133169D03*
X1643733D03*
X1640813Y1155610D03*
X1638713D03*
X1634973Y1166830D03*
X1637073D03*
X1642454Y1159350D03*
Y1166830D03*
Y1170570D03*
X1629673Y1166830D03*
X1640813Y1174310D03*
X1638713D03*
X1641633Y1178051D03*
X1639533D03*
X1642454Y1181791D03*
Y1185531D03*
Y1189271D03*
Y1193011D03*
X1659187Y436924D03*
Y433524D03*
Y430124D03*
Y440124D03*
Y443324D03*
X1648294Y1136909D03*
X1646194D03*
X1648294Y1140649D03*
X1646194D03*
X1648294Y1144389D03*
X1646194D03*
X1652034Y1155610D03*
X1649934D03*
X1652034Y1159350D03*
X1649934D03*
X1652034Y1166830D03*
X1649934D03*
X1652034Y1170570D03*
X1649934D03*
X1659514Y1157480D03*
X1657414D03*
X1659514Y1161220D03*
X1657414D03*
X1659514Y1164960D03*
X1657414D03*
X1659514Y1168700D03*
X1657414D03*
X1659514Y1172440D03*
X1657414D03*
X1644554Y1159350D03*
Y1166830D03*
Y1170570D03*
X1652034Y1174310D03*
X1649934D03*
X1656594Y1181791D03*
X1654494D03*
X1649114D03*
X1651214D03*
X1644554D03*
Y1185531D03*
Y1189271D03*
Y1193011D03*
X1661287Y436924D03*
Y433524D03*
Y430124D03*
Y440124D03*
Y443324D03*
X1769937Y1073611D03*
X1772037D03*
X1769857Y1076717D03*
X1771957D03*
X1769858Y1090841D03*
X1771958D03*
X1789492Y1091246D03*
X1791592D03*
G54D30*
X68232Y822718D03*
X59870Y905500D03*
Y901500D03*
X71836Y876608D03*
X78948Y874859D03*
X88664Y664443D03*
X196583Y594400D03*
Y602400D03*
Y598400D03*
Y606400D03*
Y610400D03*
Y614400D03*
X219208Y623398D03*
X243992Y427029D03*
Y435029D03*
Y431029D03*
X277483Y388000D03*
Y384500D03*
X271846Y442606D03*
Y446606D03*
X273153Y463479D03*
X283983Y388000D03*
X289954Y455152D03*
Y451152D03*
X282138Y463235D03*
X391760Y1392591D03*
X391465Y1485778D03*
X390858Y1482239D03*
X403122Y1297965D03*
X397987Y1307238D03*
X404491Y1313443D03*
X398461Y1497835D03*
X425191Y1366972D03*
X416367Y1541221D03*
Y1547198D03*
X438817Y333907D03*
X439147Y342874D03*
X438035Y349675D03*
X432755Y1389026D03*
Y1385026D03*
X458681Y1197471D03*
X448389Y1293045D03*
X464684Y644087D03*
X471355Y1193471D03*
X490976Y791025D03*
X507124Y697405D03*
X506369Y712755D03*
Y708755D03*
X496417Y1024165D03*
X496405Y1028165D03*
X517740Y831662D03*
X516810Y901500D03*
Y905500D03*
X528966Y600790D03*
X525207Y671119D03*
X537224Y792649D03*
X528776Y876608D03*
X535888Y874859D03*
X544187Y830889D03*
Y835389D03*
X585286Y936807D03*
X653669Y594400D03*
Y602400D03*
Y598400D03*
Y606400D03*
Y610400D03*
Y614400D03*
X700002Y766471D03*
Y753471D03*
X699988Y771159D03*
Y784659D03*
X734569Y388000D03*
Y384500D03*
X730239Y463479D03*
X741069Y388000D03*
X747040Y455152D03*
Y451152D03*
X739224Y463235D03*
X783175Y1442282D03*
X783135Y1446194D03*
X799251Y1436240D03*
X812950Y915705D03*
X806117Y1429135D03*
X830604Y848986D03*
X830061Y880390D03*
X816877Y869079D03*
X821480Y893885D03*
X825831Y921393D03*
X818415Y920026D03*
X843747Y847531D03*
X843220Y863413D03*
X843267Y871459D03*
X843220Y867413D03*
X844127Y1454159D03*
X849831Y827419D03*
X856742Y863459D03*
Y859459D03*
Y871459D03*
Y879459D03*
Y867459D03*
X856733Y875468D03*
X856776Y892738D03*
X856773Y887707D03*
X856742Y883459D03*
X867313Y869142D03*
X865732Y878942D03*
X886727Y1456859D03*
X903932Y556363D03*
X903650Y892455D03*
X903634Y884516D03*
X926263Y371739D03*
X914482Y578394D03*
X914432Y582863D03*
X914482Y586616D03*
X917411Y817982D03*
X917311Y822083D03*
X930679Y360129D03*
X930307Y366617D03*
X937042Y1394627D03*
Y1398427D03*
Y1402227D03*
Y1406027D03*
X960416Y923116D03*
X974316Y901500D03*
Y905500D03*
X992942Y768775D03*
X985862Y876608D03*
X1000690Y870398D03*
X1026902Y933822D03*
X1036789Y324752D03*
X1036768Y337736D03*
X1036835Y333519D03*
X1030278Y954222D03*
X1091773Y1537257D03*
X1101283Y1513398D03*
X1110756Y594400D03*
Y602400D03*
Y598400D03*
Y606400D03*
Y610400D03*
Y614400D03*
X1131658Y768859D03*
X1148968Y800642D03*
Y806642D03*
X1158165Y427029D03*
Y431029D03*
Y435029D03*
X1187326Y463479D03*
X1198156Y388000D03*
X1191656Y384500D03*
Y388000D03*
X1204127Y455152D03*
Y451152D03*
X1196311Y463235D03*
X1201202Y953789D03*
Y982789D03*
X1279200Y905173D03*
X1299483Y879800D03*
X1290947Y885651D03*
X1299483Y887800D03*
Y883800D03*
X1299937Y911478D03*
X1305983Y944000D03*
X1341402Y336999D03*
X1341732Y345966D03*
X1340620Y352767D03*
X1372855Y1197471D03*
X1368683Y1422900D03*
X1385916Y561000D03*
Y607500D03*
X1385529Y1193471D03*
X1405122Y961181D03*
X1410489Y1024254D03*
Y1028267D03*
X1430983Y905500D03*
Y901500D03*
X1445016Y601079D03*
X1442949Y876608D03*
X1443483Y931500D03*
Y936000D03*
X1450061Y874859D03*
X1494529Y327200D03*
X1494983Y318000D03*
X1488046Y880839D03*
Y870339D03*
X1495046Y880839D03*
Y870339D03*
X1482499Y959013D03*
X1501983Y920000D03*
X1508946Y958240D03*
Y962740D03*
X1567843Y602400D03*
Y598400D03*
Y594400D03*
Y606400D03*
Y610400D03*
Y614400D03*
X1615252Y427029D03*
Y431029D03*
Y435029D03*
X1643106Y442606D03*
Y446606D03*
X1644413Y463479D03*
X1655243Y388000D03*
X1648743D03*
Y384500D03*
X1653398Y463235D03*
X1661214Y455152D03*
Y451152D03*
X1801546Y964660D03*
X1792457Y989590D03*
X1804922Y985060D03*
G54D31*
X79028Y883233D03*
X69028D03*
X71528D03*
X76528D03*
X74028D03*
X84028D03*
X81528D03*
X84028Y904833D03*
X76528D03*
X69028D03*
X81528D03*
X79028D03*
X74028D03*
X71528D03*
X86528Y883233D03*
Y904833D03*
X535968Y883233D03*
X525968D03*
X528468D03*
X533468D03*
X530968D03*
X538468D03*
X533468Y904833D03*
X525968D03*
X538468D03*
X535968D03*
X530968D03*
X528468D03*
X543468Y883233D03*
X540968D03*
Y904833D03*
X543468D03*
X993054Y883233D03*
X983054D03*
X985554D03*
X990554D03*
X988054D03*
X990554Y904833D03*
X983054D03*
X993054D03*
X988054D03*
X985554D03*
X1000554Y883233D03*
X998054D03*
X995554D03*
X998054Y904833D03*
X1000554D03*
X995554D03*
X1440141Y883233D03*
X1442641D03*
X1447641D03*
X1445141D03*
X1447641Y904833D03*
X1440141D03*
X1445141D03*
X1442641D03*
X1450141Y883233D03*
X1457641D03*
X1455141D03*
X1452641D03*
X1455141Y904833D03*
X1457641D03*
X1452641D03*
X1450141D03*
G54D40*
X227803Y616063D03*
Y623543D03*
X237449Y616063D03*
Y619803D03*
Y623543D03*
G54D13*
X17874Y1041679D03*
X26360D03*
X48093D03*
X39607D03*
X440077Y1234726D03*
X448563D03*
X478786D03*
X487272D03*
X864564Y1050682D03*
X873050D03*
X894783D03*
X886297D03*
X928541D03*
X937027D03*
X958760D03*
X950274D03*
X1362737Y1234726D03*
X1354251D03*
X1392960D03*
X1401446D03*
X1772521Y1051168D03*
X1781007D03*
X1802740D03*
X1794254D03*
G54D22*
X28216Y1323770D03*
X96116Y21782D03*
X105562Y825539D03*
X521365Y331801D03*
X658199Y944517D03*
X787032Y1631625D03*
X828878Y560702D03*
X906500Y61964D03*
X1244161Y960023D03*
X1308242Y547162D03*
X1349086Y176019D03*
X1680546Y34636D03*
X1779102Y1562706D03*
X1795900Y852600D03*
G54D14*
X15424Y1041679D03*
X28810D03*
X37157D03*
X50543D03*
X437627Y1234726D03*
X451013D03*
X476336D03*
X489722D03*
X862114Y1050682D03*
X875500D03*
X897233D03*
X883847D03*
X926091D03*
X947824D03*
X939477D03*
X961210D03*
X1351801Y1234726D03*
X1365187D03*
X1390510D03*
X1403896D03*
X1770071Y1051168D03*
X1783457D03*
X1791804D03*
X1805190D03*
G54D50*
X408231Y1384896D03*
X418561Y1305317D03*
G54D41*
X230754Y633125D03*
Y635684D03*
Y638243D03*
X238234Y635684D03*
Y633125D03*
Y638243D03*
G54D23*
X35744Y1498350D03*
X23451Y1534239D03*
X49049Y842234D03*
X43871Y1498355D03*
X51446Y1498614D03*
X59104Y871118D03*
X63745Y880158D03*
X64007Y1219595D03*
X94962Y868330D03*
X99055Y868297D03*
X95352Y897516D03*
X91387D03*
X163539Y1135425D03*
X220500Y544016D03*
X243593Y599597D03*
X291444Y1176566D03*
X302457Y448721D03*
X298507D03*
X298125Y1139165D03*
Y1146645D03*
X391757Y1377966D03*
X408459Y1355067D03*
X404459D03*
X399959D03*
X402189Y1407662D03*
X406189D03*
X404052Y1550463D03*
X423904Y347500D03*
X425433Y1109414D03*
X410866Y1285879D03*
X414431Y1326874D03*
X418431D03*
X412779Y1365150D03*
X423517Y1376093D03*
X414203Y1410818D03*
X418203D03*
X415823Y1556287D03*
X428785Y1115912D03*
X431620Y1108989D03*
X437912Y1289289D03*
X436485Y1319310D03*
X454591Y1007282D03*
X447091Y1014282D03*
X443591D03*
X457577Y1109409D03*
X460913Y1115912D03*
X463966Y1108911D03*
X478907Y1024143D03*
X484115Y1023985D03*
X491069Y1109422D03*
X494372Y1115912D03*
X496372Y1108912D03*
X515381Y685902D03*
X513775Y673471D03*
X517775D03*
X509791Y717432D03*
X520685Y880158D03*
X516044Y871118D03*
X523200Y1109434D03*
X532248Y684313D03*
X533023Y715258D03*
X525241Y793665D03*
X534241Y822665D03*
X525741Y821165D03*
X526500Y1115912D03*
X528500Y1108912D03*
X556174Y787931D03*
X548665Y844834D03*
X555995Y868297D03*
X551902Y868330D03*
X548327Y897516D03*
X552292D03*
X558241Y840665D03*
X566231Y844812D03*
X566103Y956323D03*
X583501Y811064D03*
X620866Y1135425D03*
X677586Y544016D03*
X748531Y1176566D03*
X759543Y448721D03*
X755593D03*
X755212Y1139165D03*
Y1146645D03*
X783659Y1019428D03*
X774367Y1451106D03*
X799631Y1019428D03*
X795631D03*
X800067Y961544D03*
X803673Y1019428D03*
X807673D03*
X811673D03*
X815673D03*
X825490Y886988D03*
X832258Y906565D03*
X825146Y969664D03*
X819673Y1019428D03*
X823673D03*
X827673D03*
X831673D03*
X835000Y763016D03*
X839000Y756016D03*
X835000Y781016D03*
X839000Y774016D03*
X835000Y799016D03*
X839000Y792016D03*
Y810016D03*
X835000Y817016D03*
X836258Y906601D03*
X832952Y942814D03*
X836952D03*
X880054Y761350D03*
X874851D03*
Y774074D03*
X880054Y774064D03*
X875095Y789792D03*
X894167Y590744D03*
X886610Y761349D03*
X885110Y774059D03*
X884894Y789792D03*
X894116D03*
X887916Y803406D03*
X912665Y353623D03*
X898384Y590811D03*
X907151Y590765D03*
X903766Y820506D03*
X899816D03*
X911286Y908853D03*
X903286D03*
X907286D03*
X918819Y368887D03*
X925755Y834472D03*
X916628Y922642D03*
X920628D03*
X924628D03*
X928628D03*
X937428Y205239D03*
X931124Y834472D03*
X931261Y880643D03*
X938752Y882077D03*
X932628Y922642D03*
X936628D03*
X949058Y919977D03*
X973130Y871118D03*
X977771Y880158D03*
X971672Y1228573D03*
X980081Y360398D03*
X1008988Y868330D03*
X1005413Y897516D03*
X1007719Y953338D03*
X1020345Y341217D03*
X1013081Y868297D03*
X1013897Y897212D03*
X1028830Y341160D03*
X1055521Y1435441D03*
X1077952Y1135425D03*
X1134673Y544016D03*
X1164197Y794426D03*
X1169697D03*
X1177431Y871329D03*
Y878829D03*
X1181151Y923550D03*
X1177186Y930550D03*
X1181151D03*
X1189219Y943305D03*
X1182779Y968759D03*
X1189219Y989805D03*
X1192431Y871329D03*
Y878829D03*
X1191151Y923550D03*
X1195118Y930550D03*
X1193219Y943305D03*
X1201219D03*
X1197219D03*
X1191151Y930550D03*
X1202719Y967805D03*
X1193219Y989805D03*
X1205617Y1176566D03*
X1216630Y448721D03*
X1212680D03*
X1207219Y967805D03*
X1212298Y1139165D03*
Y1146645D03*
X1269733Y864488D03*
X1289032Y863876D03*
X1315000Y816516D03*
X1319500D03*
X1326489Y350592D03*
X1324000Y816516D03*
X1328500D03*
X1333000D03*
X1342000D03*
X1346500D03*
X1351000D03*
X1337500D03*
X1342500Y918016D03*
X1346500D03*
X1350500D03*
X1342959Y1115912D03*
X1339685Y1109410D03*
X1344959Y1108912D03*
X1358500Y918016D03*
X1354500D03*
X1362500D03*
X1366500D03*
X1361265Y1014282D03*
X1357765D03*
X1373500Y816516D03*
X1382500Y918016D03*
X1370500D03*
X1378500D03*
X1368765Y1007282D03*
X1375087Y1115912D03*
X1371792Y1109411D03*
X1377087Y1108912D03*
X1386295Y918016D03*
X1393081Y1024143D03*
X1398289Y1023985D03*
X1408546Y1115912D03*
X1405189Y1109409D03*
X1410546Y1108912D03*
X1430444Y599741D03*
X1430217Y871118D03*
X1434858Y880158D03*
X1440674Y1115912D03*
X1437352Y1109435D03*
X1442674Y1108912D03*
X1462500Y897516D03*
X1470168Y868297D03*
X1466075Y868330D03*
X1466465Y897516D03*
X1491107Y884708D03*
X1487107D03*
X1490000Y921016D03*
X1490500Y948516D03*
X1499000Y950016D03*
X1513424Y972185D03*
X1525000Y893016D03*
X1529000D03*
X1520933Y915282D03*
X1523000Y968016D03*
X1533244Y971592D03*
X1535039Y1135425D03*
X1591760Y544016D03*
X1600008Y1480769D03*
X1596038D03*
X1669767Y448721D03*
X1673717D03*
X1669385Y1139165D03*
Y1146645D03*
X1662704Y1176566D03*
X1817832Y1209498D03*
G54D32*
X173829Y455492D03*
Y583957D03*
X202844Y455492D03*
Y583957D03*
X266841Y421555D03*
Y550020D03*
X295856Y421555D03*
Y550020D03*
X630915Y455492D03*
Y583957D03*
X659930Y455492D03*
Y583957D03*
X723927Y421555D03*
Y550020D03*
X752942Y421555D03*
Y550020D03*
X1088002Y455492D03*
Y583957D03*
X1117017Y455492D03*
Y583957D03*
X1181014Y421555D03*
Y550020D03*
X1210029Y421555D03*
Y550020D03*
X1545089Y455492D03*
Y583957D03*
X1574104Y455492D03*
Y583957D03*
X1638101Y421555D03*
Y550020D03*
X1667116Y421555D03*
Y550020D03*
G54D42*
X232944Y1123810D03*
Y1129610D03*
X232916Y1205884D03*
Y1200084D03*
X404934Y324379D03*
Y318579D03*
X417325Y1217782D03*
Y1211982D03*
X424563Y1217782D03*
Y1211982D03*
X411816Y1217782D03*
Y1211982D03*
X425874Y1277211D03*
Y1283011D03*
X417305Y1362459D03*
Y1368259D03*
X439934Y1198371D03*
Y1192571D03*
X430101Y1217782D03*
Y1211982D03*
X438005Y1217782D03*
Y1211982D03*
X441044Y1277232D03*
Y1283032D03*
X436291Y1277232D03*
Y1283032D03*
X431114Y1277510D03*
Y1283310D03*
X450470Y1211982D03*
Y1217782D03*
X455811Y1211982D03*
Y1217782D03*
X443840D03*
Y1211982D03*
X456438Y1277339D03*
Y1283139D03*
X451343Y1277319D03*
Y1283119D03*
X446212Y1277264D03*
Y1283064D03*
X471348Y1211982D03*
Y1217782D03*
X466241Y1211982D03*
Y1217782D03*
X461014Y1211982D03*
Y1217782D03*
X461643Y1277361D03*
Y1283161D03*
X466973Y1277361D03*
Y1283161D03*
X472590Y1277361D03*
Y1283161D03*
X476577Y1211982D03*
Y1217782D03*
X482888Y1211982D03*
Y1217782D03*
X489047D03*
Y1211982D03*
X489119Y1277361D03*
Y1283161D03*
X478099Y1277361D03*
Y1283161D03*
X483501Y1277361D03*
Y1283161D03*
X496768Y1217782D03*
Y1211982D03*
X502202Y1217782D03*
Y1211982D03*
X494899Y1279035D03*
Y1284835D03*
X506026Y1279035D03*
Y1284835D03*
X500300Y1279035D03*
Y1284835D03*
X523741Y816549D03*
Y810749D03*
X513136Y1198371D03*
Y1192571D03*
X515463Y1217782D03*
Y1211982D03*
X510190Y1217782D03*
Y1211982D03*
X523694Y1217782D03*
Y1211982D03*
X522765Y1277845D03*
Y1283645D03*
X517332Y1277845D03*
Y1283645D03*
X511876Y1277845D03*
Y1283645D03*
X528136Y1277845D03*
Y1283645D03*
X547039Y681536D03*
X542084Y681459D03*
X547039Y687336D03*
X542084Y687259D03*
X690031Y1123810D03*
Y1129610D03*
X690003Y1205884D03*
Y1200084D03*
X877949Y566263D03*
Y560463D03*
X894949Y553963D03*
X889949D03*
X882949Y560463D03*
Y566263D03*
X894949Y559763D03*
X889949D03*
X887949Y599963D03*
Y605763D03*
X915949Y566463D03*
Y572263D03*
X914949Y603963D03*
Y609763D03*
X925114Y1095109D03*
Y1100909D03*
X930167Y1095126D03*
Y1100926D03*
X939435Y825288D03*
Y819488D03*
X942796Y872268D03*
Y878068D03*
X945889Y1095016D03*
Y1100816D03*
X940701Y1095023D03*
Y1100823D03*
X935430Y1095120D03*
Y1100920D03*
X994920Y326054D03*
Y331854D03*
X1147117Y1123810D03*
Y1129610D03*
X1147089Y1200084D03*
Y1205884D03*
X1307519Y327471D03*
Y321671D03*
X1307691Y828067D03*
Y822267D03*
X1317009Y1217914D03*
Y1212114D03*
X1311699Y1251496D03*
Y1245696D03*
X1320072Y1280152D03*
Y1285952D03*
X1314618Y1280207D03*
Y1286007D03*
X1329350Y1217914D03*
Y1212114D03*
X1323915Y1217914D03*
Y1212114D03*
X1335873Y1284287D03*
X1325444D03*
X1330594D03*
X1335873Y1290087D03*
X1325444D03*
X1330594D03*
X1352163Y1212114D03*
Y1217914D03*
X1344332D03*
Y1212114D03*
X1341137Y1284287D03*
X1346371D03*
X1351668D03*
X1341137Y1290087D03*
X1346371D03*
X1351668D03*
X1364623Y1212114D03*
Y1217914D03*
X1357630D03*
Y1212114D03*
X1356871Y1284287D03*
X1367681D03*
X1362269D03*
X1356871Y1290087D03*
X1367681D03*
X1362269D03*
X1380372Y1212114D03*
Y1217914D03*
X1375161Y1212114D03*
Y1217914D03*
X1369945Y1212114D03*
Y1217914D03*
X1373032Y1284243D03*
X1380311Y1276377D03*
Y1282177D03*
X1373032Y1290043D03*
X1396780Y896111D03*
Y901911D03*
X1397096Y1212114D03*
Y1217914D03*
X1390655Y1212114D03*
Y1217914D03*
X1385539Y1212114D03*
Y1217914D03*
X1385497Y1276433D03*
Y1282233D03*
X1400803Y1277849D03*
Y1283649D03*
X1390647Y1276399D03*
Y1282199D03*
X1395671Y1276397D03*
Y1282197D03*
X1411434Y1217914D03*
Y1212114D03*
X1416583Y1217914D03*
Y1212114D03*
X1403080Y1217914D03*
Y1212114D03*
X1412392Y1277962D03*
Y1283762D03*
X1407232Y1277952D03*
Y1283752D03*
X1427310Y1198371D03*
Y1192571D03*
X1424856Y1217914D03*
Y1212114D03*
X1430129Y1217914D03*
Y1212114D03*
X1418280Y1273336D03*
Y1279136D03*
X1430336Y1273336D03*
Y1279136D03*
X1424852Y1273336D03*
Y1279136D03*
X1438360Y1217914D03*
Y1212114D03*
X1436251Y1273336D03*
Y1279136D03*
X1442192Y1273336D03*
Y1279136D03*
X1488500Y943900D03*
Y938100D03*
X1604204Y1123810D03*
Y1129610D03*
X1604176Y1200084D03*
Y1205884D03*
G54D15*
X15023Y1070592D03*
X9223D03*
X15023Y1065299D03*
X9223D03*
X15076Y1075972D03*
X9276D03*
X14968Y1081286D03*
X9168D03*
X14970Y1086527D03*
X9170D03*
X14974Y1091945D03*
X9174D03*
X33686Y1086732D03*
X47137Y1064774D03*
X52937D03*
X39486Y1086732D03*
X166249Y1125408D03*
X172049D03*
X185369Y1189089D03*
X191169D03*
X208242Y1162291D03*
X214042D03*
X223203D03*
X229003D03*
X241904D03*
X247704D03*
X295198Y1163090D03*
X300998D03*
X311962Y1163079D03*
X306162D03*
X435198Y1314391D03*
X440998D03*
X501412Y681478D03*
X507212D03*
X501412Y687978D03*
X507212D03*
X502655Y693245D03*
X508455D03*
X521414Y717903D03*
X514383Y723583D03*
X520183D03*
X527214Y717903D03*
X532304Y797889D03*
X538104D03*
Y803389D03*
X532304D03*
X551804Y806889D03*
Y801389D03*
X557604Y806889D03*
Y801389D03*
X625146Y1126058D03*
X630946D03*
X642456Y1189089D03*
X648256D03*
X665329Y1162291D03*
X680290D03*
X686090D03*
X671129D03*
X698991D03*
X704791D03*
X752285Y1163090D03*
X758085D03*
X763249Y1163079D03*
X769049D03*
X860009Y1073297D03*
X854209D03*
X859852Y1089261D03*
X854052D03*
X859847Y1083918D03*
X854047D03*
X859989Y1078510D03*
X854189D03*
X859778Y1100734D03*
X853978D03*
X859827Y1094715D03*
X854027D03*
X868191Y827563D03*
X873991D03*
X868191Y822176D03*
X873991D03*
X868191Y833037D03*
X873991D03*
X881648Y1093445D03*
X893856Y1074510D03*
X887448Y1093445D03*
X900049Y551863D03*
X905849D03*
X912866Y832855D03*
X907066D03*
X899656Y1074510D03*
X921549Y572863D03*
X927349D03*
X927014Y1074367D03*
X921214D03*
X927095Y1085168D03*
X921295D03*
X926987Y1079821D03*
X921187D03*
X936229Y843950D03*
X942029D03*
X941933Y849373D03*
X936133D03*
X960850Y807855D03*
X955050D03*
X960850Y813342D03*
X955050D03*
X960850Y818829D03*
X955050D03*
X1009116Y316394D03*
X997020Y336954D03*
X1002820D03*
Y341954D03*
X997020D03*
X1003520Y348954D03*
X1009320D03*
Y353954D03*
X1003520D03*
X1021743Y306927D03*
X1027543D03*
X1014916Y316394D03*
X1043020Y343954D03*
X1052820Y316954D03*
X1047020D03*
X1048820Y343954D03*
X1086222Y1125408D03*
X1080422D03*
X1089700Y1521000D03*
X1105342Y1189089D03*
X1099542D03*
X1095500Y1521000D03*
X1122415Y1162291D03*
X1137376D03*
X1128215D03*
X1156077D03*
X1143176D03*
X1161877D03*
X1220335Y1163079D03*
X1215171Y1163090D03*
X1209371D03*
X1226135Y1163079D03*
X1287605Y897416D03*
X1300974Y846670D03*
X1299184Y863988D03*
X1293405Y897416D03*
X1306774Y846670D03*
X1304984Y863988D03*
X1378578Y1258399D03*
X1372778D03*
X1390449Y854121D03*
X1396249D03*
X1388924Y880908D03*
X1394724D03*
X1497063Y925240D03*
Y930740D03*
X1502863Y925240D03*
Y930740D03*
X1522363Y928740D03*
X1516563D03*
Y934240D03*
X1522363D03*
X1543309Y1125408D03*
X1537509D03*
X1562429Y1189089D03*
X1556629D03*
X1579502Y1162291D03*
X1594463D03*
X1585302D03*
X1600263D03*
X1618964D03*
X1613164D03*
X1672258Y1163090D03*
X1666458D03*
X1677422Y1163079D03*
X1683222D03*
X1773994Y1080874D03*
X1768194D03*
X1773915Y1086114D03*
X1768115D03*
X1773915Y1101159D03*
X1768115D03*
X1774017Y1095803D03*
X1768217D03*
X1788794Y1095629D03*
X1783536Y1101077D03*
X1789336D03*
X1802379Y1074480D03*
X1794594Y1095629D03*
X1808179Y1074480D03*
G54D51*
X401341Y1375546D03*
X403310D03*
X405278D03*
X407247D03*
X409215D03*
X401341Y1394246D03*
X403310D03*
X405278D03*
X407247D03*
X409215D03*
X413640Y1295967D03*
X411671D03*
X419545D03*
X421514D03*
X423482D03*
X425451D03*
X415608D03*
X417577D03*
X425451Y1314667D03*
X413640D03*
X423482D03*
X419545D03*
X411671D03*
X421514D03*
X417577D03*
X415608D03*
X411184Y1375546D03*
X413152D03*
X415121D03*
X411184Y1394246D03*
X413152D03*
X415121D03*
G54D24*
X35744Y1501317D03*
X23451Y1537206D03*
X49049Y845201D03*
X51446Y1501581D03*
X43871Y1501322D03*
X59104Y874085D03*
X63745Y883125D03*
X64007Y1222562D03*
X94962Y871297D03*
X99055Y871264D03*
X95352Y900483D03*
X91387D03*
X163539Y1138392D03*
X220500Y546983D03*
X243593Y602564D03*
X291444Y1179533D03*
X302457Y451688D03*
X298507D03*
X298125Y1142132D03*
Y1149612D03*
X391757Y1380933D03*
X408459Y1358034D03*
X404459D03*
X399959D03*
X402189Y1410629D03*
X406189D03*
X404052Y1553430D03*
X423904Y350467D03*
X425433Y1112381D03*
X410866Y1288846D03*
X414431Y1329841D03*
X418431D03*
X412779Y1368117D03*
X423517Y1379060D03*
X414203Y1413785D03*
X418203D03*
X415823Y1559254D03*
X428785Y1118879D03*
X431620Y1111956D03*
X437912Y1292256D03*
X436485Y1322277D03*
X454591Y1010249D03*
X447091Y1017249D03*
X443591D03*
X457577Y1112376D03*
X460913Y1118879D03*
X463966Y1111878D03*
X478907Y1027110D03*
X484115Y1026952D03*
X491069Y1112389D03*
X494372Y1118879D03*
X496372Y1111879D03*
X513775Y676438D03*
X517775D03*
X515381Y688869D03*
X509791Y720399D03*
X516044Y874085D03*
X520685Y883125D03*
X523200Y1112401D03*
X532248Y687280D03*
X533023Y718225D03*
X525241Y796632D03*
X534241Y825632D03*
X525741Y824132D03*
X526500Y1118879D03*
X528500Y1111879D03*
X556174Y790898D03*
X548665Y847801D03*
X555995Y871264D03*
X551902Y871297D03*
X548327Y900483D03*
X552292D03*
X558241Y843632D03*
X566231Y847779D03*
X566103Y959290D03*
X583501Y814031D03*
X620866Y1138392D03*
X677586Y546983D03*
X748531Y1179533D03*
X759543Y451688D03*
X755593D03*
X755212Y1142132D03*
Y1149612D03*
X783659Y1022395D03*
X774367Y1454073D03*
X799631Y1022395D03*
X795631D03*
X800067Y964511D03*
X803673Y1022395D03*
X807673D03*
X811673D03*
X815673D03*
X825490Y889955D03*
X832258Y909532D03*
X825146Y972631D03*
X819673Y1022395D03*
X823673D03*
X827673D03*
X831673D03*
X835000Y765983D03*
X839000Y758983D03*
Y776983D03*
X835000Y783983D03*
X839000Y794983D03*
X835000Y801983D03*
X839000Y812983D03*
X835000Y819983D03*
X836258Y909568D03*
X832952Y945781D03*
X836952D03*
X880054Y764317D03*
X874851D03*
Y777041D03*
X880054Y777031D03*
X875095Y792759D03*
X894167Y593711D03*
X886610Y764316D03*
X885110Y777026D03*
X884894Y792759D03*
X894116D03*
X887916Y806373D03*
X912665Y356590D03*
X898384Y593778D03*
X907151Y593732D03*
X903766Y823473D03*
X899816D03*
X911286Y911820D03*
X903286D03*
X907286D03*
X918819Y371854D03*
X925755Y837439D03*
X916628Y925609D03*
X920628D03*
X924628D03*
X928628D03*
X937428Y208206D03*
X931124Y837439D03*
X938752Y885044D03*
X931261Y883610D03*
X932628Y925609D03*
X936628D03*
X949058Y922944D03*
X973130Y874085D03*
X977771Y883125D03*
X971672Y1231540D03*
X980081Y363365D03*
X1008988Y871297D03*
X1005413Y900483D03*
X1007719Y956305D03*
X1020345Y344184D03*
X1013081Y871264D03*
X1013897Y900179D03*
X1028830Y344127D03*
X1055521Y1438408D03*
X1077952Y1138392D03*
X1134673Y546983D03*
X1164197Y797393D03*
X1169697D03*
X1177431Y874296D03*
Y881796D03*
X1181151Y926517D03*
X1177186Y933517D03*
X1181151D03*
X1189219Y946272D03*
X1182779Y971726D03*
X1189219Y992772D03*
X1192431Y874296D03*
Y881796D03*
X1191151Y926517D03*
X1195118Y933517D03*
X1191151D03*
X1193219Y946272D03*
X1201219D03*
X1197219D03*
X1202719Y970772D03*
X1193219Y992772D03*
X1205617Y1179533D03*
X1216630Y451688D03*
X1212680D03*
X1207219Y970772D03*
X1212298Y1142132D03*
Y1149612D03*
X1269733Y867455D03*
X1289032Y866843D03*
X1315000Y819483D03*
X1319500D03*
X1326489Y353559D03*
X1324000Y819483D03*
X1328500D03*
X1333000D03*
X1342000D03*
X1346500D03*
X1351000D03*
X1337500D03*
X1342500Y920983D03*
X1346500D03*
X1350500D03*
X1342959Y1118879D03*
X1339685Y1112377D03*
X1344959Y1111879D03*
X1358500Y920983D03*
X1354500D03*
X1362500D03*
X1366500D03*
X1361265Y1017249D03*
X1357765D03*
X1373500Y819483D03*
X1382500Y920983D03*
X1370500D03*
X1378500D03*
X1368765Y1010249D03*
X1375087Y1118879D03*
X1371792Y1112378D03*
X1377087Y1111879D03*
X1386295Y920983D03*
X1393081Y1027110D03*
X1398289Y1026952D03*
X1408546Y1118879D03*
X1405189Y1112376D03*
X1410546Y1111879D03*
X1430444Y602708D03*
X1430217Y874085D03*
X1434858Y883125D03*
X1440674Y1118879D03*
X1437352Y1112402D03*
X1442674Y1111879D03*
X1462500Y900483D03*
X1470168Y871264D03*
X1466075Y871297D03*
X1466465Y900483D03*
X1491107Y887675D03*
X1487107D03*
X1490000Y923983D03*
X1490500Y951483D03*
X1499000Y952983D03*
X1513424Y975152D03*
X1525000Y895983D03*
X1529000D03*
X1520933Y918249D03*
X1523000Y970983D03*
X1533244Y974559D03*
X1535039Y1138392D03*
X1591760Y546983D03*
X1600008Y1483736D03*
X1596038D03*
X1669767Y451688D03*
X1673717D03*
X1669385Y1142132D03*
Y1149612D03*
X1662704Y1179533D03*
X1817832Y1212465D03*
G54D60*
X895384Y228740D03*
Y276772D03*
X923336Y226772D03*
Y278740D03*
G54D33*
X190325Y368760D03*
X279360Y636752D03*
X647411Y368760D03*
X736446Y636752D03*
X1104498Y368760D03*
X1193533Y636752D03*
X1561585Y368760D03*
X1650620Y636752D03*
G54D25*
X28774Y1529931D03*
Y1522774D03*
X63624Y847627D03*
X59871Y897500D03*
X61977Y1511735D03*
X63463Y1525714D03*
X63487Y1518596D03*
X63437Y1531804D03*
X90097Y681800D03*
X98773Y875194D03*
Y879194D03*
X118577Y892845D03*
Y884845D03*
Y888845D03*
X159189Y1148530D03*
X159648Y1164560D03*
X159433Y1160650D03*
X159648Y1169100D03*
X183084Y550400D03*
Y554400D03*
X193870Y544967D03*
X196584Y618400D03*
X200870Y544967D03*
X261628Y438323D03*
X251025Y427017D03*
X250993Y435029D03*
Y431029D03*
X283984Y384500D03*
X282156Y467367D03*
X306767Y377912D03*
Y389912D03*
Y381912D03*
Y385912D03*
Y393924D03*
Y397912D03*
Y401924D03*
Y405924D03*
Y409924D03*
X392639Y1311289D03*
Y1315289D03*
X388462Y1384722D03*
Y1388722D03*
X395795Y1299275D03*
Y1303275D03*
X400001Y1540700D03*
Y1535200D03*
Y1547200D03*
X420633Y343005D03*
X421054Y334523D03*
X421564Y1111226D03*
X425491Y1288843D03*
X425192Y1370972D03*
X431177Y349696D03*
X438307Y1309865D03*
X428437Y1320684D03*
X433066Y1398800D03*
X433042Y1394934D03*
X453585Y1111226D03*
X458682Y1193471D03*
X448390Y1301545D03*
Y1297045D03*
Y1305545D03*
X462369Y1007325D03*
X459269Y1002180D03*
X467575Y1014566D03*
X471356Y1197471D03*
X490977Y795025D03*
X487036Y1111177D03*
X506370Y704755D03*
X500091Y790275D03*
X509225Y796149D03*
X515420Y799973D03*
Y811973D03*
Y803973D03*
Y807973D03*
X516811Y897500D03*
X519294Y1111272D03*
X536263Y708711D03*
X526013Y713581D03*
X532188Y831027D03*
X525188D03*
X532225Y836149D03*
Y840649D03*
X525225D03*
Y836149D03*
X531868Y849830D03*
X524868D03*
X555188Y796389D03*
X555713Y879194D03*
Y875194D03*
X575517Y888845D03*
Y884845D03*
Y892845D03*
X580884Y961804D03*
X616276Y1148530D03*
X616520Y1160650D03*
X616735Y1169100D03*
Y1164560D03*
X640170Y550400D03*
Y554400D03*
X650956Y544967D03*
X653670Y618400D03*
X657956Y544967D03*
X700003Y762971D03*
Y756971D03*
X699989Y780659D03*
Y775159D03*
X718714Y438323D03*
X728933Y442606D03*
Y446606D03*
X741070Y384500D03*
X739242Y467367D03*
X763853Y377912D03*
Y389912D03*
Y381912D03*
Y385912D03*
Y393924D03*
Y397912D03*
Y401924D03*
Y405924D03*
Y409924D03*
X806103Y1425152D03*
X806328Y1436240D03*
X802328Y1460979D03*
X831208Y859484D03*
X816878Y872812D03*
Y876605D03*
X845793Y835459D03*
Y839459D03*
X843748Y843490D03*
X843345Y855397D03*
X845793Y851459D03*
X845707Y875476D03*
X842942Y879459D03*
Y883459D03*
X842848Y891503D03*
X842849Y887490D03*
X834371Y1463690D03*
X864875Y388245D03*
X856743Y847459D03*
Y835459D03*
Y839459D03*
Y843459D03*
Y855459D03*
X856790Y851924D03*
X889535Y571532D03*
X890686Y577288D03*
X890743Y585773D03*
X886715Y1460847D03*
X903630Y888478D03*
X919957Y312228D03*
X915134Y360583D03*
X915365Y365893D03*
X926602Y1379411D03*
X926629Y1383264D03*
X926655Y1387039D03*
X926683Y1390841D03*
X936955Y1371951D03*
X937029Y1375878D03*
X941997Y1443901D03*
X974317Y897500D03*
X968042Y1444474D03*
X993684Y1369200D03*
Y1373400D03*
Y1385200D03*
Y1394200D03*
Y1389200D03*
X993655Y1398271D03*
X990227Y1444240D03*
X1010742Y327510D03*
Y323386D03*
Y333088D03*
Y339880D03*
X1005485Y801475D03*
X1009489Y816957D03*
X1012799Y875194D03*
Y879194D03*
X1014338Y1444512D03*
X1032603Y892845D03*
Y884845D03*
Y888845D03*
X1040004Y1444596D03*
X1046904Y337454D03*
X1073362Y1148530D03*
X1073821Y1164560D03*
Y1169100D03*
X1073606Y1160650D03*
X1091774Y1533457D03*
X1097257Y550400D03*
Y554400D03*
X1108043Y544967D03*
X1115043D03*
X1110757Y618400D03*
X1155501Y788431D03*
X1148969Y797142D03*
Y810142D03*
X1165198Y427017D03*
X1165166Y431029D03*
Y435029D03*
X1175801Y438323D03*
X1186020Y442606D03*
Y446606D03*
X1179636Y888899D03*
X1198157Y384500D03*
X1196329Y467367D03*
X1220940Y377912D03*
Y389912D03*
Y381912D03*
Y385912D03*
Y393924D03*
Y397912D03*
Y401924D03*
Y405924D03*
Y409924D03*
X1263714Y327257D03*
X1270621D03*
X1279484Y330500D03*
Y334500D03*
X1299484Y871800D03*
Y875800D03*
Y891800D03*
X1290948Y881802D03*
X1323639Y337615D03*
X1323254Y346026D03*
X1333762Y352788D03*
X1335514Y1111198D03*
X1367725D03*
X1376543Y1007325D03*
X1373443Y1002180D03*
X1381749Y1014566D03*
X1372856Y1193471D03*
X1385917Y569000D03*
Y565000D03*
Y615500D03*
Y611500D03*
X1397501Y984037D03*
X1385530Y1197471D03*
X1411799Y992861D03*
X1401172Y1111258D03*
X1410884Y1423700D03*
X1430984Y897500D03*
X1433415Y1111197D03*
X1443484Y927000D03*
X1469886Y879194D03*
Y875194D03*
X1473984Y923500D03*
X1480179Y927324D03*
Y931324D03*
Y939324D03*
Y935324D03*
X1490320Y891615D03*
X1496947Y958378D03*
X1489947D03*
X1496984Y963500D03*
X1489984D03*
X1496984Y968000D03*
X1489984D03*
X1489627Y977181D03*
X1496627D03*
X1500547Y876339D03*
X1519947Y923740D03*
X1525984Y943000D03*
X1518984D03*
X1530449Y1148530D03*
X1530693Y1160650D03*
X1530908Y1169100D03*
Y1164560D03*
X1554344Y550400D03*
Y554400D03*
X1551207Y1418847D03*
X1560206Y1418806D03*
X1565130Y544967D03*
X1572130D03*
X1567844Y618400D03*
X1588494Y341787D03*
Y337787D03*
X1622285Y427017D03*
X1622253Y431029D03*
Y435029D03*
X1632888Y438323D03*
X1655244Y384500D03*
X1653416Y467367D03*
X1678027Y377912D03*
Y389912D03*
Y381912D03*
Y385912D03*
Y393924D03*
Y397912D03*
Y401924D03*
Y405924D03*
Y409924D03*
G54D16*
X15713Y1116633D03*
Y1125633D03*
X15767Y1134705D03*
Y1142705D03*
X17767Y1503569D03*
X22713Y1116633D03*
Y1125633D03*
X22767Y1134705D03*
Y1142705D03*
X24767Y1503569D03*
X49542Y1110100D03*
Y1119100D03*
X49701Y1129688D03*
Y1137688D03*
X56542Y1110100D03*
Y1119100D03*
X56701Y1129688D03*
Y1137688D03*
X398190Y1093068D03*
X405190D03*
X398184Y1085881D03*
X405184D03*
X397068Y1291261D03*
X404068D03*
X425725Y1331356D03*
X439744Y1093088D03*
X432725Y1331356D03*
X446744Y1093088D03*
X463777Y1093068D03*
X470777D03*
X505331Y1093088D03*
X505189Y1085890D03*
X512331Y1093088D03*
X512189Y1085890D03*
X862403Y1125636D03*
Y1134636D03*
X862580Y1152080D03*
Y1144080D03*
X869403Y1125636D03*
Y1134636D03*
X869580Y1152080D03*
Y1144080D03*
X896232Y1119103D03*
Y1128103D03*
X896701Y1141169D03*
Y1149169D03*
X903232Y1119103D03*
Y1128103D03*
X903701Y1141169D03*
Y1149169D03*
X926380Y1125636D03*
Y1134636D03*
X926558Y1143708D03*
Y1151708D03*
X933380Y1125636D03*
Y1134636D03*
X933558Y1143708D03*
Y1151708D03*
X960209Y1119103D03*
X960678Y1141169D03*
X960209Y1128103D03*
X960678Y1149169D03*
X967209Y1119103D03*
X967678Y1141169D03*
X967209Y1128103D03*
X967678Y1149169D03*
X1312364Y1093068D03*
X1319364D03*
X1312358Y1085881D03*
X1319358D03*
X1360918Y1093088D03*
X1353918D03*
X1377951Y1093068D03*
X1384951D03*
X1426363Y1085890D03*
X1419363D03*
X1426505Y1093088D03*
X1419505D03*
X1776360Y1126122D03*
X1783360D03*
X1776360Y1135122D03*
X1783360D03*
X1776360Y1151822D03*
X1783360D03*
X1776360Y1143822D03*
X1783360D03*
X1815189Y1119589D03*
X1808189D03*
X1815189Y1128589D03*
X1808189D03*
X1815189Y1140912D03*
X1808189D03*
X1815189Y1148912D03*
X1808189D03*
G54D34*
X195570Y1156430D03*
X191830D03*
X188090Y1144389D03*
Y1146489D03*
Y1151870D03*
Y1153970D03*
X195570Y1158530D03*
X188090Y1159050D03*
Y1156950D03*
X191830Y1158530D03*
X188090Y1172210D03*
Y1161850D03*
Y1163950D03*
X195570Y1171390D03*
X188090Y1168930D03*
Y1166830D03*
X191830Y1171390D03*
X188090Y1174310D03*
X195570Y1173490D03*
X191830D03*
X188100Y1185300D03*
Y1183200D03*
Y1178250D03*
Y1180350D03*
X197500Y1188451D03*
Y1186351D03*
X212401Y1133989D03*
Y1136089D03*
X204921Y1133989D03*
Y1136089D03*
X201181Y1133989D03*
Y1136089D03*
X203051Y1126508D03*
Y1128608D03*
X206791Y1126508D03*
Y1128608D03*
X214271Y1126508D03*
Y1128608D03*
X210531Y1126508D03*
Y1128608D03*
X208661Y1133989D03*
Y1136089D03*
X199311Y1126508D03*
Y1128608D03*
X208661Y1141469D03*
Y1143569D03*
X201181Y1141469D03*
Y1143569D03*
X204921Y1141469D03*
Y1143569D03*
X212401Y1141469D03*
Y1143569D03*
X199311Y1156430D03*
X208661Y1148949D03*
Y1151049D03*
X204921Y1148949D03*
Y1151049D03*
X201181Y1148949D03*
Y1151049D03*
X212401Y1148949D03*
Y1151049D03*
X210531Y1156430D03*
X214271D03*
X203051D03*
X206791D03*
X199311Y1158530D03*
X210531D03*
X214271D03*
X203051D03*
X206791D03*
X203051Y1171390D03*
X199311D03*
X206791D03*
X210531D03*
X214271D03*
X203051Y1173490D03*
X199311D03*
X206791D03*
X210531D03*
X214271D03*
X212401Y1188451D03*
Y1186351D03*
Y1180971D03*
Y1178871D03*
X208661Y1188451D03*
Y1186351D03*
Y1180971D03*
Y1178871D03*
X204921Y1180971D03*
Y1178871D03*
Y1188451D03*
Y1186351D03*
X201181Y1188451D03*
Y1186351D03*
Y1180971D03*
Y1178871D03*
X210315Y1203412D03*
Y1201312D03*
X202835Y1203412D03*
Y1201312D03*
X206575Y1203412D03*
Y1201312D03*
X214055Y1203412D03*
Y1201312D03*
X212401Y1195931D03*
Y1193831D03*
X208661Y1195931D03*
Y1193831D03*
X201181Y1195931D03*
Y1193831D03*
X204921Y1195931D03*
Y1193831D03*
X199095Y1203412D03*
Y1201312D03*
X231102Y1133989D03*
Y1136089D03*
X219881Y1133989D03*
Y1136089D03*
X229044Y1126508D03*
Y1128608D03*
X221751Y1126508D03*
Y1128608D03*
X225492Y1126508D03*
Y1128608D03*
X227362Y1133989D03*
Y1136089D03*
X223622Y1133989D03*
Y1136089D03*
X216141Y1133989D03*
Y1136089D03*
X218011Y1126508D03*
Y1128608D03*
X231102Y1141469D03*
Y1143569D03*
X227362Y1141469D03*
Y1143569D03*
X219881Y1141469D03*
Y1143569D03*
X223622Y1141469D03*
Y1143569D03*
X231102Y1148949D03*
Y1151049D03*
X219881Y1148949D03*
Y1151049D03*
X227362Y1148949D03*
Y1151049D03*
X223622Y1148949D03*
Y1151049D03*
X221752Y1156430D03*
X229232D03*
X225492D03*
X218011D03*
X216141Y1141469D03*
Y1143569D03*
Y1148949D03*
Y1151049D03*
X221752Y1158530D03*
X229232D03*
X225492D03*
X218011D03*
X229292Y1171390D03*
X225492D03*
X221752D03*
X218011D03*
X229292Y1173490D03*
X225492D03*
X221752D03*
X218011D03*
X223622Y1180971D03*
Y1178871D03*
X219881Y1188451D03*
Y1186351D03*
X223622Y1188451D03*
Y1186351D03*
X231102Y1180971D03*
Y1178871D03*
Y1188451D03*
Y1186351D03*
X227362Y1180971D03*
Y1178871D03*
Y1188451D03*
Y1186351D03*
X219881Y1180971D03*
Y1178871D03*
X216141Y1180971D03*
Y1178871D03*
Y1188451D03*
Y1186351D03*
X229016Y1203412D03*
Y1201312D03*
X231102Y1195931D03*
Y1193831D03*
X223622Y1195931D03*
Y1193831D03*
X227362Y1195931D03*
Y1193831D03*
X219881Y1195931D03*
Y1193831D03*
X225276Y1203412D03*
Y1201312D03*
X221535Y1203412D03*
Y1201312D03*
X217795Y1203412D03*
Y1201312D03*
X216141Y1195931D03*
Y1193831D03*
X238582Y1133989D03*
Y1136089D03*
X246062Y1133989D03*
Y1136089D03*
X244192Y1126508D03*
Y1128608D03*
X240452Y1126508D03*
Y1128608D03*
X236844Y1126508D03*
Y1128608D03*
X234842Y1133989D03*
Y1136089D03*
X242322Y1133989D03*
Y1136089D03*
Y1148949D03*
Y1151049D03*
X244192Y1156430D03*
X236712D03*
X240452D03*
X246062Y1148949D03*
Y1151049D03*
X234842Y1148949D03*
Y1151049D03*
X238582Y1148949D03*
Y1151049D03*
X246062Y1141469D03*
Y1143569D03*
X238582Y1141469D03*
Y1143569D03*
X234842Y1141469D03*
Y1143569D03*
X242322Y1141469D03*
Y1143569D03*
X244192Y1158530D03*
X236712D03*
X240452D03*
Y1171390D03*
X244192D03*
X236712D03*
X240452Y1173490D03*
X244192D03*
X236712D03*
X242322Y1180971D03*
Y1178871D03*
Y1188451D03*
Y1186351D03*
X246062Y1188451D03*
Y1186351D03*
X238582Y1180971D03*
Y1178871D03*
X234842Y1188451D03*
Y1186351D03*
X246062Y1180971D03*
Y1178871D03*
X238582Y1188451D03*
Y1186351D03*
X234842Y1180971D03*
Y1178871D03*
X246062Y1195931D03*
Y1193831D03*
X234842Y1195931D03*
Y1193831D03*
X240556Y1203412D03*
Y1201312D03*
X236816Y1203412D03*
Y1201312D03*
X244296Y1203412D03*
Y1201312D03*
X238582Y1195931D03*
Y1193831D03*
X242322Y1195931D03*
Y1193831D03*
X251673Y1126508D03*
Y1128608D03*
X255413Y1126508D03*
Y1128608D03*
X262893Y1126508D03*
Y1128608D03*
X261023Y1133989D03*
Y1136089D03*
X249803Y1133989D03*
Y1136089D03*
X257283Y1133989D03*
Y1136089D03*
X253543Y1133989D03*
Y1136089D03*
X259153Y1126508D03*
Y1128608D03*
X247933Y1126508D03*
Y1128608D03*
X259153Y1156430D03*
X261023Y1148949D03*
Y1151049D03*
X257283Y1148949D03*
Y1151049D03*
X262900Y1156430D03*
X249803Y1148949D03*
Y1151049D03*
X247932Y1156430D03*
X261023Y1141469D03*
Y1143569D03*
X257283Y1141469D03*
Y1143569D03*
X249803Y1141469D03*
Y1143569D03*
X253543Y1141469D03*
Y1143569D03*
Y1148949D03*
Y1151049D03*
X255413Y1156430D03*
X251673D03*
X259153Y1158530D03*
X262900D03*
X251673Y1171390D03*
X262893D03*
X259153D03*
X247933D03*
X255413D03*
X247932Y1158530D03*
X255413D03*
X251673D03*
Y1173490D03*
X262893D03*
X259153D03*
X247933D03*
X255413D03*
X249803Y1180971D03*
Y1178871D03*
Y1188451D03*
Y1186351D03*
X253543Y1180971D03*
Y1178871D03*
Y1188451D03*
Y1186351D03*
X261023Y1188451D03*
Y1186351D03*
X257283Y1188451D03*
Y1186351D03*
X261023Y1180971D03*
Y1178871D03*
X257283Y1180971D03*
Y1178871D03*
X262997Y1203412D03*
Y1201312D03*
X253543Y1195931D03*
Y1193831D03*
X259257Y1203412D03*
Y1201312D03*
X255517Y1203412D03*
Y1201312D03*
X251777Y1203412D03*
Y1201312D03*
X249803Y1195931D03*
Y1193831D03*
X261023Y1195931D03*
Y1193831D03*
X257283Y1195931D03*
Y1193831D03*
X248037Y1203412D03*
Y1201312D03*
X266633Y1126508D03*
Y1128608D03*
X264763Y1133989D03*
Y1136089D03*
Y1148949D03*
Y1151049D03*
Y1141469D03*
Y1143569D03*
Y1188451D03*
Y1186351D03*
Y1180971D03*
Y1178871D03*
Y1195931D03*
Y1193831D03*
X274114Y1196751D03*
Y1198851D03*
X266737Y1203412D03*
Y1201312D03*
X274114Y1204232D03*
Y1202132D03*
X395951Y1213350D03*
Y1215450D03*
X399246Y1213268D03*
Y1215368D03*
X406296Y1214005D03*
Y1216105D03*
X402595Y1213240D03*
Y1215340D03*
X506275Y1214181D03*
Y1216281D03*
X519673Y1214181D03*
Y1216281D03*
X531235Y1214210D03*
Y1216310D03*
X528129Y1214181D03*
Y1216281D03*
X645177Y1145209D03*
Y1147309D03*
Y1152350D03*
Y1154450D03*
X652657Y1156430D03*
X648917D03*
X652657Y1158530D03*
X645177Y1159350D03*
Y1157250D03*
X648917Y1158530D03*
X645177Y1172210D03*
Y1162150D03*
Y1164250D03*
X652657Y1171390D03*
X645177Y1169350D03*
Y1167250D03*
X648917Y1171390D03*
X645177Y1174310D03*
X652657Y1173490D03*
X648917D03*
X645177Y1185531D03*
Y1183431D03*
Y1178051D03*
Y1180151D03*
X658268Y1133989D03*
Y1136089D03*
X667618Y1126508D03*
Y1128608D03*
X663878Y1126508D03*
Y1128608D03*
X660138Y1126508D03*
Y1128608D03*
X665748Y1133989D03*
Y1136089D03*
X662008Y1133989D03*
Y1136089D03*
X669488Y1133989D03*
Y1136089D03*
X656398Y1126508D03*
Y1128608D03*
X665748Y1141469D03*
Y1143569D03*
X658268Y1141469D03*
Y1143569D03*
X662008Y1141469D03*
Y1143569D03*
X669488Y1141469D03*
Y1143569D03*
X656398Y1156430D03*
X663878D03*
X658268Y1148949D03*
Y1151049D03*
X665748Y1148949D03*
Y1151049D03*
X662008Y1148949D03*
Y1151049D03*
X669488Y1148949D03*
Y1151049D03*
X667618Y1156430D03*
X660138D03*
X656398Y1158530D03*
X663878D03*
X667618D03*
X660138D03*
Y1171390D03*
X663878D03*
X656398D03*
X667618D03*
X660138Y1173490D03*
X663878D03*
X656398D03*
X667618D03*
X658268Y1188451D03*
Y1186351D03*
X665748Y1180971D03*
Y1178871D03*
X662008Y1180971D03*
Y1178871D03*
Y1188451D03*
Y1186351D03*
X658268Y1180971D03*
Y1178871D03*
X669488Y1188451D03*
Y1186351D03*
Y1180971D03*
Y1178871D03*
X665748Y1188451D03*
Y1186351D03*
X654587Y1188451D03*
Y1186351D03*
X663878Y1203412D03*
Y1201312D03*
X667618Y1203412D03*
Y1201312D03*
X669488Y1195931D03*
Y1193831D03*
X665748Y1195931D03*
Y1193831D03*
X658268Y1195931D03*
Y1193831D03*
X662008Y1195931D03*
Y1193831D03*
X660138Y1203412D03*
Y1201312D03*
X656398Y1203412D03*
Y1201312D03*
X673228Y1133989D03*
Y1136089D03*
X684449Y1133989D03*
Y1136089D03*
X678838Y1126508D03*
Y1128608D03*
X675098Y1126508D03*
Y1128608D03*
X682579Y1126508D03*
Y1128608D03*
X680709Y1133989D03*
Y1136089D03*
X676968Y1133989D03*
Y1136089D03*
X671358Y1126508D03*
Y1128608D03*
X680709Y1141469D03*
Y1143569D03*
X684449Y1141469D03*
Y1143569D03*
X673228Y1141469D03*
Y1143569D03*
X676968Y1141469D03*
Y1143569D03*
X673228Y1148949D03*
Y1151049D03*
X682579Y1156430D03*
X671358D03*
X675098D03*
X678838D03*
X684449Y1148949D03*
Y1151049D03*
X680709Y1148949D03*
Y1151049D03*
X676968Y1148949D03*
Y1151049D03*
X682579Y1158530D03*
X671358D03*
X675098D03*
X678838D03*
X675098Y1171390D03*
X671358D03*
X682579D03*
X678838D03*
X675098Y1173490D03*
X671358D03*
X682579D03*
X678838D03*
X676968Y1188451D03*
Y1186351D03*
X673228Y1180971D03*
Y1178871D03*
X680709Y1188451D03*
Y1186351D03*
X673228Y1188451D03*
Y1186351D03*
X684449Y1180971D03*
Y1178871D03*
Y1188451D03*
Y1186351D03*
X676968Y1180971D03*
Y1178871D03*
X680709Y1180971D03*
Y1178871D03*
X675098Y1203412D03*
Y1201312D03*
X684449Y1195931D03*
Y1193831D03*
X680709Y1195931D03*
Y1193831D03*
X676968Y1195931D03*
Y1193831D03*
X673228Y1195931D03*
Y1193831D03*
X682579Y1203412D03*
Y1201312D03*
X678838Y1203412D03*
Y1201312D03*
X671358Y1203412D03*
Y1201312D03*
X701279Y1126508D03*
Y1128608D03*
X686131Y1126508D03*
Y1128608D03*
X695669Y1133989D03*
Y1136089D03*
X699409Y1133989D03*
Y1136089D03*
X691929Y1133989D03*
Y1136089D03*
X688189Y1133989D03*
Y1136089D03*
X697539Y1126508D03*
Y1128608D03*
X693931Y1126508D03*
Y1128608D03*
X699409Y1148949D03*
Y1151049D03*
X693799Y1156430D03*
X701279D03*
X697539D03*
X686319D03*
X688189Y1148949D03*
Y1151049D03*
X691929Y1148949D03*
Y1151049D03*
X695669Y1148949D03*
Y1151049D03*
X688189Y1141469D03*
Y1143569D03*
X695669Y1141469D03*
Y1143569D03*
X691929Y1141469D03*
Y1143569D03*
X699409Y1141469D03*
Y1143569D03*
X693799Y1158530D03*
X701279D03*
X697539D03*
X686319D03*
X697539Y1171390D03*
X701279D03*
X693799D03*
X686319D03*
X697539Y1173490D03*
X701279D03*
X693799D03*
X686319D03*
X699409Y1180971D03*
Y1178871D03*
X691929Y1180971D03*
Y1178871D03*
Y1188451D03*
Y1186351D03*
X695669Y1188451D03*
Y1186351D03*
X688189Y1180971D03*
Y1178871D03*
Y1188451D03*
Y1186351D03*
X699409Y1188451D03*
Y1186351D03*
X695669Y1180971D03*
Y1178871D03*
X688189Y1195931D03*
Y1193831D03*
X695669Y1195931D03*
Y1193831D03*
X691929Y1195931D03*
Y1193831D03*
X699409Y1195931D03*
Y1193831D03*
X693903Y1203412D03*
Y1201312D03*
X697539Y1203412D03*
Y1201312D03*
X701279Y1203412D03*
Y1201312D03*
X686103Y1203412D03*
Y1201312D03*
X703149Y1133989D03*
Y1136089D03*
X705020Y1126508D03*
Y1128608D03*
X712500Y1126508D03*
Y1128608D03*
X708760Y1126508D03*
Y1128608D03*
X718110Y1133989D03*
Y1136089D03*
X716240Y1126508D03*
Y1128608D03*
X710630Y1133989D03*
Y1136089D03*
X714370Y1133989D03*
Y1136089D03*
X706890Y1133989D03*
Y1136089D03*
X703149Y1141469D03*
Y1143569D03*
X705020Y1156430D03*
X703149Y1148949D03*
Y1151049D03*
X706890Y1141469D03*
Y1143569D03*
X710630Y1141469D03*
Y1143569D03*
X718110Y1141469D03*
Y1143569D03*
X714370Y1141469D03*
Y1143569D03*
X716240Y1156430D03*
X708760D03*
X712500D03*
X718110Y1148949D03*
Y1151049D03*
X710630Y1148949D03*
Y1151049D03*
X706890Y1148949D03*
Y1151049D03*
X714370Y1148949D03*
Y1151049D03*
X712500Y1171390D03*
X705020Y1158530D03*
X716240D03*
X708760D03*
X712500D03*
X716240Y1171390D03*
X708760D03*
X705020D03*
X712500Y1173490D03*
X706890Y1188451D03*
Y1186351D03*
X718110Y1180971D03*
Y1178871D03*
Y1188451D03*
Y1186351D03*
X714370Y1180971D03*
Y1178871D03*
Y1188451D03*
Y1186351D03*
X710630Y1180971D03*
Y1178871D03*
X706890Y1180971D03*
Y1178871D03*
X710630Y1188451D03*
Y1186351D03*
X703149Y1180971D03*
Y1178871D03*
Y1188451D03*
Y1186351D03*
X716240Y1173490D03*
X708760D03*
X705020D03*
X706890Y1195931D03*
Y1193831D03*
X708760Y1203412D03*
Y1201312D03*
X712500Y1203412D03*
Y1201312D03*
X710630Y1195931D03*
Y1193831D03*
X705020Y1203412D03*
Y1201312D03*
X714370Y1195931D03*
Y1193831D03*
X716240Y1203412D03*
Y1201312D03*
X718110Y1195931D03*
Y1193831D03*
X703149Y1195931D03*
Y1193831D03*
X723720Y1126508D03*
Y1128608D03*
X721850Y1133989D03*
Y1136089D03*
X719980Y1126508D03*
Y1128608D03*
X721850Y1141469D03*
Y1143569D03*
Y1148949D03*
Y1151049D03*
X719980Y1156430D03*
Y1171390D03*
Y1158530D03*
Y1173490D03*
X721850Y1180971D03*
Y1178871D03*
Y1188451D03*
Y1186351D03*
Y1195931D03*
Y1193831D03*
X719980Y1203412D03*
Y1201312D03*
X723720Y1203412D03*
Y1201312D03*
X731201Y1196751D03*
Y1198851D03*
Y1204232D03*
Y1202132D03*
X873257Y1103056D03*
Y1100956D03*
X876877Y1103058D03*
Y1100958D03*
X870004Y1103014D03*
Y1100914D03*
X951421Y1098057D03*
Y1095957D03*
X1106003Y1156430D03*
X1102263Y1151870D03*
Y1153970D03*
Y1144389D03*
Y1146489D03*
X1106003Y1171390D03*
X1102263Y1172210D03*
Y1168930D03*
Y1166830D03*
Y1161850D03*
Y1163950D03*
Y1159050D03*
Y1156950D03*
X1106003Y1158530D03*
X1102273Y1185300D03*
Y1183200D03*
Y1178250D03*
Y1180350D03*
X1106003Y1173490D03*
X1102263Y1174310D03*
X1122834Y1133989D03*
Y1136089D03*
X1119094Y1133989D03*
Y1136089D03*
X1115354Y1133989D03*
Y1136089D03*
X1120964Y1126508D03*
Y1128608D03*
X1117224Y1126508D03*
Y1128608D03*
X1113484Y1126508D03*
Y1128608D03*
X1120964Y1156430D03*
X1117224D03*
X1113484D03*
X1109743D03*
X1122834Y1148949D03*
Y1151049D03*
X1119094Y1148949D03*
Y1151049D03*
X1115354Y1148949D03*
Y1151049D03*
X1122834Y1141469D03*
Y1143569D03*
X1115354Y1141469D03*
Y1143569D03*
X1119094Y1141469D03*
Y1143569D03*
X1120964Y1171390D03*
X1117224D03*
X1113484D03*
X1109743D03*
X1120964Y1158530D03*
X1117224D03*
X1113484D03*
X1109743D03*
X1122834Y1188451D03*
Y1186351D03*
X1119094Y1188451D03*
Y1186351D03*
X1115354Y1188451D03*
Y1186351D03*
X1111673Y1188451D03*
Y1186351D03*
X1122834Y1180971D03*
Y1178871D03*
X1119094Y1180971D03*
Y1178871D03*
X1115354Y1180971D03*
Y1178871D03*
X1120964Y1173490D03*
X1117224D03*
X1113484D03*
X1109743D03*
X1124488Y1203412D03*
Y1201312D03*
X1120748Y1203412D03*
Y1201312D03*
X1117008Y1203412D03*
Y1201312D03*
X1113268Y1203412D03*
Y1201312D03*
X1122834Y1195931D03*
Y1193831D03*
X1119094Y1195931D03*
Y1193831D03*
X1115354Y1195931D03*
Y1193831D03*
X1137795Y1133989D03*
Y1136089D03*
X1134054Y1133989D03*
Y1136089D03*
X1130314Y1133989D03*
Y1136089D03*
X1126574Y1133989D03*
Y1136089D03*
X1139665Y1126508D03*
Y1128608D03*
X1135924Y1126508D03*
Y1128608D03*
X1132184Y1126508D03*
Y1128608D03*
X1128444Y1126508D03*
Y1128608D03*
X1124704Y1126508D03*
Y1128608D03*
X1139665Y1156430D03*
X1135925D03*
X1132184D03*
X1128444D03*
X1124704D03*
X1137795Y1148949D03*
Y1151049D03*
X1134054Y1148949D03*
Y1151049D03*
X1130314Y1148949D03*
Y1151049D03*
X1126574Y1148949D03*
Y1151049D03*
X1137795Y1141469D03*
Y1143569D03*
X1134054Y1141469D03*
Y1143569D03*
X1130314Y1141469D03*
Y1143569D03*
X1126574Y1141469D03*
Y1143569D03*
X1139665Y1171390D03*
X1135925D03*
X1132184D03*
X1128444D03*
X1124704D03*
X1139665Y1158530D03*
X1135925D03*
X1132184D03*
X1128444D03*
X1124704D03*
X1137795Y1188451D03*
Y1186351D03*
X1134054Y1188451D03*
Y1186351D03*
X1130314Y1188451D03*
Y1186351D03*
X1126574Y1188451D03*
Y1186351D03*
X1137795Y1180971D03*
Y1178871D03*
X1134054Y1180971D03*
Y1178871D03*
X1130314Y1180971D03*
Y1178871D03*
X1126574Y1180971D03*
Y1178871D03*
X1139665Y1173490D03*
X1135925D03*
X1132184D03*
X1128444D03*
X1124704D03*
X1139449Y1203412D03*
Y1201312D03*
X1135708Y1203412D03*
Y1201312D03*
X1131968Y1203412D03*
Y1201312D03*
X1128228Y1203412D03*
Y1201312D03*
X1137795Y1195931D03*
Y1193831D03*
X1134054Y1195931D03*
Y1193831D03*
X1130314Y1195931D03*
Y1193831D03*
X1126574Y1195931D03*
Y1193831D03*
X1156495Y1133989D03*
Y1136089D03*
X1152755Y1133989D03*
Y1136089D03*
X1149015Y1133989D03*
Y1136089D03*
X1145275Y1133989D03*
Y1136089D03*
X1141535Y1133989D03*
Y1136089D03*
X1154625Y1126508D03*
Y1128608D03*
X1150885Y1126508D03*
Y1128608D03*
X1143405Y1126508D03*
Y1128608D03*
X1154625Y1156430D03*
X1150885D03*
X1143405D03*
X1156495Y1148949D03*
Y1151049D03*
X1152755Y1148949D03*
Y1151049D03*
X1149015Y1148949D03*
Y1151049D03*
X1145275Y1148949D03*
Y1151049D03*
X1141535Y1148949D03*
Y1151049D03*
X1152755Y1141469D03*
Y1143569D03*
X1156495Y1141469D03*
Y1143569D03*
X1149015Y1141469D03*
Y1143569D03*
X1145275Y1141469D03*
Y1143569D03*
X1141535Y1141469D03*
Y1143569D03*
X1154625Y1171390D03*
X1150885D03*
X1143465D03*
X1154625Y1158530D03*
X1150885D03*
X1143405D03*
X1156495Y1188451D03*
Y1186351D03*
X1152755Y1188451D03*
Y1186351D03*
X1149015Y1188451D03*
Y1186351D03*
X1145275Y1188451D03*
Y1186351D03*
X1141535Y1188451D03*
Y1186351D03*
X1156495Y1180971D03*
Y1178871D03*
X1152755Y1180971D03*
Y1178871D03*
X1149015Y1180971D03*
Y1178871D03*
X1145275Y1180971D03*
Y1178871D03*
X1141535Y1180971D03*
Y1178871D03*
X1154625Y1173490D03*
X1150885D03*
X1143465D03*
X1154729Y1203412D03*
Y1201312D03*
X1150989Y1203412D03*
Y1201312D03*
X1143189Y1203412D03*
Y1201312D03*
X1156495Y1195931D03*
Y1193831D03*
X1152755Y1195931D03*
Y1193831D03*
X1149015Y1195931D03*
Y1193831D03*
X1145275Y1195931D03*
Y1193831D03*
X1141535Y1195931D03*
Y1193831D03*
X1171456Y1133989D03*
Y1136089D03*
X1167716Y1133989D03*
Y1136089D03*
X1163976Y1133989D03*
Y1136089D03*
X1160235Y1133989D03*
Y1136089D03*
X1169586Y1126508D03*
Y1128608D03*
X1165846Y1126508D03*
Y1128608D03*
X1162106Y1126508D03*
Y1128608D03*
X1158365Y1126508D03*
Y1128608D03*
X1169586Y1156430D03*
X1165846D03*
X1162105D03*
X1158365D03*
X1171456Y1148949D03*
Y1151049D03*
X1167716Y1148949D03*
Y1151049D03*
X1163976Y1148949D03*
Y1151049D03*
X1160235Y1148949D03*
Y1151049D03*
X1171456Y1141469D03*
Y1143569D03*
X1167716Y1141469D03*
Y1143569D03*
X1160235Y1141469D03*
Y1143569D03*
X1163976Y1141469D03*
Y1143569D03*
X1169586Y1171390D03*
X1165846D03*
X1162106D03*
X1158365D03*
X1169586Y1158530D03*
X1165846D03*
X1162105D03*
X1158365D03*
X1171456Y1188451D03*
Y1186351D03*
X1167716Y1188451D03*
Y1186351D03*
X1163976Y1188451D03*
Y1186351D03*
X1160235Y1188451D03*
Y1186351D03*
X1171456Y1180971D03*
Y1178871D03*
X1167716Y1180971D03*
Y1178871D03*
X1163976Y1180971D03*
Y1178871D03*
X1160235Y1180971D03*
Y1178871D03*
X1169586Y1173490D03*
X1165846D03*
X1162106D03*
X1158365D03*
X1169690Y1203412D03*
Y1201312D03*
X1165950Y1203412D03*
Y1201312D03*
X1162210Y1203412D03*
Y1201312D03*
X1158469Y1203412D03*
Y1201312D03*
X1171456Y1195931D03*
Y1193831D03*
X1167716Y1195931D03*
Y1193831D03*
X1163976Y1195931D03*
Y1193831D03*
X1160235Y1195931D03*
Y1193831D03*
X1178936Y1133989D03*
Y1136089D03*
X1175196Y1133989D03*
Y1136089D03*
X1180806Y1126508D03*
Y1128608D03*
X1177066Y1126508D03*
Y1128608D03*
X1173326Y1126508D03*
Y1128608D03*
X1177073Y1156430D03*
X1173326D03*
X1178936Y1148949D03*
Y1151049D03*
X1175196Y1148949D03*
Y1151049D03*
X1178936Y1141469D03*
Y1143569D03*
X1175196Y1141469D03*
Y1143569D03*
X1177066Y1171390D03*
X1173326D03*
X1177073Y1158530D03*
X1173326D03*
X1178936Y1188451D03*
Y1186351D03*
X1175196Y1188451D03*
Y1186351D03*
X1178936Y1180971D03*
Y1178871D03*
X1175196Y1180971D03*
Y1178871D03*
X1177066Y1173490D03*
X1173326D03*
X1188287Y1204232D03*
Y1202132D03*
Y1196751D03*
Y1198851D03*
X1180910Y1203412D03*
Y1201312D03*
X1177170Y1203412D03*
Y1201312D03*
X1173430Y1203412D03*
Y1201312D03*
X1178936Y1195931D03*
Y1193831D03*
X1175196Y1195931D03*
Y1193831D03*
X1312962Y1213613D03*
Y1215713D03*
X1310791Y1275725D03*
Y1273625D03*
X1333734Y1214501D03*
Y1216601D03*
X1340056Y1214492D03*
Y1216592D03*
X1336913Y1214487D03*
Y1216587D03*
X1420941Y1214217D03*
Y1216317D03*
X1445901Y1214246D03*
Y1216346D03*
X1442795Y1214217D03*
Y1216317D03*
X1434339Y1214217D03*
Y1216317D03*
X1559350Y1151870D03*
Y1153970D03*
Y1144389D03*
Y1146489D03*
X1563090Y1156430D03*
X1559350Y1172210D03*
Y1168930D03*
Y1166830D03*
Y1161850D03*
Y1163950D03*
Y1159050D03*
Y1156950D03*
X1563090Y1171390D03*
Y1158530D03*
X1559360Y1185300D03*
Y1183200D03*
Y1178250D03*
Y1180350D03*
X1559350Y1174310D03*
X1563090Y1173490D03*
X1570571Y1126508D03*
Y1128608D03*
X1572441Y1133989D03*
Y1136089D03*
X1574311Y1126508D03*
Y1128608D03*
X1578051Y1126508D03*
Y1128608D03*
X1576181Y1133989D03*
Y1136089D03*
X1572441Y1141469D03*
Y1143569D03*
Y1148949D03*
Y1151049D03*
X1566830Y1156430D03*
X1570571D03*
X1576181Y1141469D03*
Y1143569D03*
Y1148949D03*
Y1151049D03*
X1574311Y1156430D03*
X1578051D03*
X1566830Y1171390D03*
X1570571D03*
X1574311D03*
X1578051D03*
X1566830Y1158530D03*
X1570571D03*
X1574311D03*
X1578051D03*
X1572441Y1180971D03*
Y1178871D03*
X1568760Y1188451D03*
Y1186351D03*
X1572441Y1188451D03*
Y1186351D03*
X1576181Y1180971D03*
Y1178871D03*
Y1188451D03*
Y1186351D03*
X1566830Y1173490D03*
X1570571D03*
X1574311D03*
X1578051D03*
X1572441Y1195931D03*
Y1193831D03*
X1570355Y1203412D03*
Y1201312D03*
X1576181Y1195931D03*
Y1193831D03*
X1574095Y1203412D03*
Y1201312D03*
X1577835Y1203412D03*
Y1201312D03*
X1581791Y1126508D03*
Y1128608D03*
X1585531Y1126508D03*
Y1128608D03*
X1589271Y1126508D03*
Y1128608D03*
X1579921Y1133989D03*
Y1136089D03*
X1583661Y1133989D03*
Y1136089D03*
X1587401Y1133989D03*
Y1136089D03*
X1593011Y1126508D03*
Y1128608D03*
X1591141Y1133989D03*
Y1136089D03*
X1594882Y1133989D03*
Y1136089D03*
X1579921Y1141469D03*
Y1143569D03*
X1583661Y1141469D03*
Y1143569D03*
X1587401Y1141469D03*
Y1143569D03*
X1579921Y1148949D03*
Y1151049D03*
X1583661Y1148949D03*
Y1151049D03*
X1587401Y1148949D03*
Y1151049D03*
X1581791Y1156430D03*
X1585531D03*
X1589271D03*
X1591141Y1141469D03*
Y1143569D03*
X1594882Y1141469D03*
Y1143569D03*
X1591141Y1148949D03*
Y1151049D03*
X1594882Y1148949D03*
Y1151049D03*
X1593012Y1156430D03*
X1581791Y1171390D03*
X1585531D03*
X1589271D03*
X1593012D03*
X1581791Y1158530D03*
X1585531D03*
X1589271D03*
X1593012D03*
X1579921Y1180971D03*
Y1178871D03*
X1583661Y1180971D03*
Y1178871D03*
X1587401Y1180971D03*
Y1178871D03*
X1579921Y1188451D03*
Y1186351D03*
X1583661Y1188451D03*
Y1186351D03*
X1587401Y1188451D03*
Y1186351D03*
X1591141Y1180971D03*
Y1178871D03*
X1594882Y1180971D03*
Y1178871D03*
X1591141Y1188451D03*
Y1186351D03*
X1594882Y1188451D03*
Y1186351D03*
X1581791Y1173490D03*
X1585531D03*
X1589271D03*
X1593012D03*
X1579921Y1195931D03*
Y1193831D03*
X1583661Y1195931D03*
Y1193831D03*
X1587401Y1195931D03*
Y1193831D03*
X1581575Y1203412D03*
Y1201312D03*
X1585315Y1203412D03*
Y1201312D03*
X1589055Y1203412D03*
Y1201312D03*
X1591141Y1195931D03*
Y1193831D03*
X1594882Y1195931D03*
Y1193831D03*
X1592795Y1203412D03*
Y1201312D03*
X1596752Y1126508D03*
Y1128608D03*
X1600492Y1126508D03*
Y1128608D03*
X1598622Y1133989D03*
Y1136089D03*
X1602362Y1133989D03*
Y1136089D03*
X1606102Y1133989D03*
Y1136089D03*
X1607972Y1126508D03*
Y1128608D03*
X1611712Y1126508D03*
Y1128608D03*
X1609842Y1133989D03*
Y1136089D03*
X1598622Y1141469D03*
Y1143569D03*
X1602362Y1141469D03*
Y1143569D03*
X1606102Y1141469D03*
Y1143569D03*
X1598622Y1148949D03*
Y1151049D03*
X1602362Y1148949D03*
Y1151049D03*
X1606102Y1148949D03*
Y1151049D03*
X1596752Y1156430D03*
X1600492D03*
X1609842Y1141469D03*
Y1143569D03*
Y1148949D03*
Y1151049D03*
X1607972Y1156430D03*
X1611712D03*
X1596752Y1171390D03*
X1600552D03*
X1607972D03*
X1611712D03*
X1596752Y1158530D03*
X1600492D03*
X1607972D03*
X1611712D03*
X1598622Y1180971D03*
Y1178871D03*
X1602362Y1180971D03*
Y1178871D03*
X1606102Y1180971D03*
Y1178871D03*
X1598622Y1188451D03*
Y1186351D03*
X1602362Y1188451D03*
Y1186351D03*
X1606102Y1188451D03*
Y1186351D03*
X1609842Y1180971D03*
Y1178871D03*
Y1188451D03*
Y1186351D03*
X1596752Y1173490D03*
X1600552D03*
X1607972D03*
X1611712D03*
X1598622Y1195931D03*
Y1193831D03*
X1602362Y1195931D03*
Y1193831D03*
X1606102Y1195931D03*
Y1193831D03*
X1596536Y1203412D03*
Y1201312D03*
X1600276Y1203412D03*
Y1201312D03*
X1609842Y1195931D03*
Y1193831D03*
X1608076Y1203412D03*
Y1201312D03*
X1611816Y1203412D03*
Y1201312D03*
X1615452Y1126508D03*
Y1128608D03*
X1619193Y1126508D03*
Y1128608D03*
X1613582Y1133989D03*
Y1136089D03*
X1617322Y1133989D03*
Y1136089D03*
X1621063Y1133989D03*
Y1136089D03*
X1622933Y1126508D03*
Y1128608D03*
X1626673Y1126508D03*
Y1128608D03*
X1624803Y1133989D03*
Y1136089D03*
X1613582Y1141469D03*
Y1143569D03*
X1617322Y1141469D03*
Y1143569D03*
X1621063Y1141469D03*
Y1143569D03*
X1613582Y1148949D03*
Y1151049D03*
X1617322Y1148949D03*
Y1151049D03*
X1621063Y1148949D03*
Y1151049D03*
X1615452Y1156430D03*
X1619192D03*
X1624803Y1141469D03*
Y1143569D03*
Y1148949D03*
Y1151049D03*
X1622933Y1156430D03*
X1626673D03*
X1615452Y1171390D03*
X1619193D03*
X1622933D03*
X1626673D03*
X1615452Y1158530D03*
X1619192D03*
X1622933D03*
X1626673D03*
X1613582Y1180971D03*
Y1178871D03*
X1617322Y1180971D03*
Y1178871D03*
X1621063Y1180971D03*
Y1178871D03*
X1613582Y1188451D03*
Y1186351D03*
X1617322Y1188451D03*
Y1186351D03*
X1621063Y1188451D03*
Y1186351D03*
X1624803Y1180971D03*
Y1178871D03*
Y1188451D03*
Y1186351D03*
X1615452Y1173490D03*
X1619193D03*
X1622933D03*
X1626673D03*
X1613582Y1195931D03*
Y1193831D03*
X1617322Y1195931D03*
Y1193831D03*
X1621063Y1195931D03*
Y1193831D03*
X1615556Y1203412D03*
Y1201312D03*
X1619297Y1203412D03*
Y1201312D03*
X1624803Y1195931D03*
Y1193831D03*
X1623037Y1203412D03*
Y1201312D03*
X1626777Y1203412D03*
Y1201312D03*
X1630413Y1126508D03*
Y1128608D03*
X1634153Y1126508D03*
Y1128608D03*
X1637893Y1126508D03*
Y1128608D03*
X1628543Y1133989D03*
Y1136089D03*
X1632283Y1133989D03*
Y1136089D03*
X1636023Y1133989D03*
Y1136089D03*
X1628543Y1141469D03*
Y1143569D03*
X1632283Y1141469D03*
Y1143569D03*
X1636023Y1141469D03*
Y1143569D03*
X1628543Y1148949D03*
Y1151049D03*
X1632283Y1148949D03*
Y1151049D03*
X1636023Y1148949D03*
Y1151049D03*
X1630413Y1156430D03*
X1634160D03*
X1630413Y1171390D03*
X1634153D03*
X1630413Y1158530D03*
X1634160D03*
X1628543Y1180971D03*
Y1178871D03*
X1632283Y1180971D03*
Y1178871D03*
X1636023Y1180971D03*
Y1178871D03*
X1628543Y1188451D03*
Y1186351D03*
X1632283Y1188451D03*
Y1186351D03*
X1636023Y1188451D03*
Y1186351D03*
X1630413Y1173490D03*
X1634153D03*
X1628543Y1195931D03*
Y1193831D03*
X1632283Y1195931D03*
Y1193831D03*
X1636023Y1195931D03*
Y1193831D03*
X1630517Y1203412D03*
Y1201312D03*
X1634257Y1203412D03*
Y1201312D03*
X1637997Y1203412D03*
Y1201312D03*
X1645374Y1196751D03*
Y1198851D03*
Y1204232D03*
Y1202132D03*
G54D70*
X1153433Y782873D03*
Y772243D03*
X1157173D03*
X1160913Y782873D03*
Y772243D03*
G54D61*
X891012Y692138D03*
G54D43*
X251694Y1436156D03*
X237390Y1437236D03*
X392745Y1515756D03*
G54D52*
X419061Y1143544D03*
Y1168740D03*
X446889Y1143544D03*
Y1168740D03*
X484648Y1143544D03*
Y1168740D03*
X512476Y1143544D03*
Y1168740D03*
X1333235Y1143544D03*
Y1168740D03*
X1361063Y1143544D03*
Y1168740D03*
X1398822Y1143544D03*
Y1168740D03*
X1426650Y1143544D03*
Y1168740D03*
G54D26*
X25807Y1529931D03*
Y1522774D03*
X60657Y847627D03*
X56904Y897500D03*
X59010Y1511735D03*
X60496Y1525714D03*
X60520Y1518596D03*
X60470Y1531804D03*
X87130Y681800D03*
X95806Y875194D03*
Y879194D03*
X115610Y892845D03*
Y884845D03*
Y888845D03*
X156222Y1148530D03*
X156681Y1164560D03*
X156466Y1160650D03*
X156681Y1169100D03*
X180117Y550400D03*
Y554400D03*
X197903Y544967D03*
X190903D03*
X193617Y618400D03*
X258661Y438323D03*
X248058Y427017D03*
X248026Y435029D03*
Y431029D03*
X279189Y467367D03*
X281017Y384500D03*
X303800Y377912D03*
Y389912D03*
Y381912D03*
Y385912D03*
Y393924D03*
Y397912D03*
Y401924D03*
Y405924D03*
Y409924D03*
X392828Y1299275D03*
Y1303275D03*
X389672Y1311289D03*
Y1315289D03*
X385495Y1384722D03*
Y1388722D03*
X397034Y1540700D03*
Y1535200D03*
Y1547200D03*
X417666Y343005D03*
X418087Y334523D03*
X418597Y1111226D03*
X422524Y1288843D03*
X425470Y1320684D03*
X422225Y1370972D03*
X428210Y349696D03*
X435340Y1309865D03*
X430099Y1398800D03*
X430075Y1394934D03*
X456302Y1002180D03*
X450618Y1111226D03*
X455715Y1193471D03*
X445423Y1301545D03*
Y1297045D03*
Y1305545D03*
X459402Y1007325D03*
X464608Y1014566D03*
X468389Y1197471D03*
X488010Y795025D03*
X484069Y1111177D03*
X503403Y704755D03*
X506258Y796149D03*
X497124Y790275D03*
X523046Y713581D03*
X512453Y799973D03*
Y811973D03*
Y803973D03*
Y807973D03*
X522221Y831027D03*
X522258Y840649D03*
Y836149D03*
X521901Y849830D03*
X513844Y897500D03*
X516327Y1111272D03*
X533296Y708711D03*
X529221Y831027D03*
X529258Y836149D03*
Y840649D03*
X528901Y849830D03*
X552221Y796389D03*
X552746Y879194D03*
Y875194D03*
X572550Y888845D03*
Y884845D03*
Y892845D03*
X577917Y961804D03*
X613309Y1148530D03*
X613553Y1160650D03*
X613768Y1169100D03*
Y1164560D03*
X637203Y550400D03*
Y554400D03*
X647989Y544967D03*
X650703Y618400D03*
X654989Y544967D03*
X697036Y762971D03*
Y756971D03*
X697022Y780659D03*
Y775159D03*
X715747Y438323D03*
X725966Y442606D03*
Y446606D03*
X738103Y384500D03*
X736275Y467367D03*
X760886Y377912D03*
Y389912D03*
Y381912D03*
Y385912D03*
Y393924D03*
Y397912D03*
Y401924D03*
Y405924D03*
Y409924D03*
X799361Y1460979D03*
X813911Y872812D03*
Y876605D03*
X803136Y1425152D03*
X803361Y1436240D03*
X828241Y859484D03*
X831404Y1463690D03*
X842826Y835459D03*
Y839459D03*
X840781Y843490D03*
X840378Y855397D03*
X842826Y851459D03*
X842740Y875476D03*
X839975Y879459D03*
Y883459D03*
X839881Y891503D03*
X839882Y887490D03*
X861908Y388245D03*
X853776Y847459D03*
Y835459D03*
Y839459D03*
Y843459D03*
Y855459D03*
X853823Y851924D03*
X886568Y571532D03*
X887719Y577288D03*
X887776Y585773D03*
X883748Y1460847D03*
X912167Y360583D03*
X912398Y365893D03*
X900663Y888478D03*
X916990Y312228D03*
X923635Y1379411D03*
X923662Y1383264D03*
X923688Y1387039D03*
X923716Y1390841D03*
X933988Y1371951D03*
X934062Y1375878D03*
X939030Y1443901D03*
X971350Y897500D03*
X965075Y1444474D03*
X990717Y1369200D03*
Y1373400D03*
Y1385200D03*
Y1394200D03*
Y1389200D03*
X990688Y1398271D03*
X987260Y1444240D03*
X1007775Y327510D03*
Y323386D03*
Y333088D03*
Y339880D03*
X1002518Y801475D03*
X1006522Y816957D03*
X1009832Y875194D03*
Y879194D03*
X1011371Y1444512D03*
X1029636Y892845D03*
Y884845D03*
Y888845D03*
X1037037Y1444596D03*
X1043937Y337454D03*
X1070395Y1148530D03*
X1070854Y1164560D03*
Y1169100D03*
X1070639Y1160650D03*
X1088807Y1533457D03*
X1094290Y550400D03*
Y554400D03*
X1105076Y544967D03*
X1107790Y618400D03*
X1112076Y544967D03*
X1152534Y788431D03*
X1146002Y797142D03*
Y810142D03*
X1162231Y427017D03*
X1162199Y431029D03*
Y435029D03*
X1172834Y438323D03*
X1183053Y442606D03*
Y446606D03*
X1176669Y888899D03*
X1195190Y384500D03*
X1193362Y467367D03*
X1217973Y377912D03*
Y389912D03*
Y381912D03*
Y385912D03*
Y393924D03*
Y397912D03*
Y401924D03*
Y405924D03*
Y409924D03*
X1260747Y327257D03*
X1267654D03*
X1276517Y330500D03*
Y334500D03*
X1296517Y871800D03*
Y875800D03*
Y891800D03*
X1287981Y881802D03*
X1320672Y337615D03*
X1320287Y346026D03*
X1330795Y352788D03*
X1332547Y1111198D03*
X1364758D03*
X1382950Y569000D03*
Y565000D03*
Y615500D03*
Y611500D03*
X1373576Y1007325D03*
X1370476Y1002180D03*
X1378782Y1014566D03*
X1382563Y1197471D03*
X1369889Y1193471D03*
X1394534Y984037D03*
X1398205Y1111258D03*
X1408832Y992861D03*
X1407917Y1423700D03*
X1428017Y897500D03*
X1430448Y1111197D03*
X1440517Y927000D03*
X1466919Y879194D03*
Y875194D03*
X1471017Y923500D03*
X1477212Y927324D03*
Y931324D03*
Y939324D03*
Y935324D03*
X1497580Y876339D03*
X1487353Y891615D03*
X1493980Y958378D03*
X1486980D03*
X1494017Y963500D03*
X1487017D03*
X1494017Y968000D03*
X1487017D03*
X1486660Y977181D03*
X1493660D03*
X1516980Y923740D03*
X1523017Y943000D03*
X1516017D03*
X1527482Y1148530D03*
X1527726Y1160650D03*
X1527941Y1169100D03*
Y1164560D03*
X1551377Y550400D03*
Y554400D03*
X1562163Y544967D03*
X1548240Y1418847D03*
X1557239Y1418806D03*
X1569163Y544967D03*
X1564877Y618400D03*
X1585527Y341787D03*
Y337787D03*
X1619318Y427017D03*
X1619286Y431029D03*
Y435029D03*
X1629921Y438323D03*
X1652277Y384500D03*
X1650449Y467367D03*
X1675060Y377912D03*
Y389912D03*
Y381912D03*
Y385912D03*
Y393924D03*
Y397912D03*
Y401924D03*
Y405924D03*
Y409924D03*
G54D17*
X11184Y1503268D03*
Y1510748D03*
X51043Y1543839D03*
Y1536359D03*
X424559Y1404286D03*
Y1411766D03*
X880949Y599123D03*
Y606603D03*
X921449Y603123D03*
Y610603D03*
X988920Y326714D03*
Y334194D03*
G54D71*
X1185312Y895751D03*
X1187871D03*
Y910317D03*
X1185312D03*
X1190431Y895751D03*
X1192990D03*
X1190431Y910317D03*
X1192990D03*
G54D35*
X197247Y1544069D03*
G54D44*
X269682Y451628D03*
X275588Y458714D03*
X269682D03*
X275588Y451628D03*
X726768D03*
X732674Y458714D03*
X726768D03*
X732674Y451628D03*
X1183855D03*
X1189761Y458714D03*
X1183855D03*
X1189761Y451628D03*
X1640942D03*
Y458714D03*
X1646848D03*
Y451628D03*
G54D62*
X891031Y694107D03*
X893984Y696075D03*
X891031D03*
X893984Y692138D03*
Y694107D03*
G54D53*
X414519Y1253318D03*
Y1261804D03*
X512430Y1253318D03*
Y1261804D03*
X1328693Y1253318D03*
Y1261804D03*
X1427004Y1253810D03*
Y1262296D03*
G54D63*
X895542Y859465D03*
X892392D03*
X895542Y856316D03*
X892392D03*
X895542Y862615D03*
X892392D03*
X895542Y868914D03*
X892392D03*
X910029Y836875D03*
X906879D03*
X920739Y846867D03*
X917589D03*
X920739Y853166D03*
X917589D03*
X945122Y860671D03*
X945030Y864721D03*
X945147Y868168D03*
X948272Y860671D03*
X948180Y864721D03*
X948297Y868168D03*
X1318541Y863128D03*
X1321691D03*
X1349976Y840894D03*
X1346826D03*
X1359425Y878689D03*
X1356275D03*
X1378266Y844021D03*
X1375116D03*
X1381461Y885021D03*
X1378311D03*
X1393970Y862829D03*
X1390820D03*
X1393947Y866620D03*
X1390797D03*
X1393001Y871018D03*
X1389851D03*
X1392988Y876204D03*
X1389838D03*
G54D18*
X18037Y1512511D03*
X21537D03*
X63981Y1212146D03*
X96443Y890391D03*
X156299Y1135426D03*
X160039D03*
X220500Y536517D03*
X221263Y632670D03*
X223952Y1213969D03*
X246695Y633206D03*
X291444Y1184048D03*
X408523Y1327161D03*
X404657Y1327185D03*
X395959Y1355068D03*
X400879Y1400335D03*
X395111Y1490998D03*
X409981Y1534003D03*
X404157D03*
X424016Y328157D03*
X425773Y1265489D03*
X418735Y1282581D03*
X414735D03*
X416357Y1398966D03*
X410152Y1405470D03*
X430959Y328106D03*
X431822Y1122849D03*
X427997Y1122834D03*
X441078Y1263727D03*
X436325D03*
X431661Y1265489D03*
X432485Y1319311D03*
X450591Y1007283D03*
Y1014283D03*
X456377Y1023716D03*
X456472Y1263834D03*
X451377Y1263814D03*
X446246Y1263759D03*
X460377Y1023716D03*
X464385Y1023697D03*
X461677Y1263856D03*
X466975D03*
X472592Y1263824D03*
X489121D03*
X478101D03*
X483503D03*
X505791Y717433D03*
X497357Y1122954D03*
X493532Y1122929D03*
X494901Y1265498D03*
X505728D03*
X500302D03*
X522939Y1265583D03*
X519131Y1265582D03*
X537023Y715259D03*
X528741Y812666D03*
X530453Y1265649D03*
X526725Y1265623D03*
X545741Y798666D03*
X552665Y844835D03*
X553383Y890391D03*
X570241Y803166D03*
Y824666D03*
X562231Y844813D03*
X577501Y816565D03*
X588001D03*
X577501Y823565D03*
X588001D03*
X613386Y1135426D03*
X617126D03*
X677586Y536517D03*
X681039Y1213969D03*
X748531Y1184048D03*
X780631Y1450177D03*
X787631Y1019429D03*
X791686D03*
X801082Y1451083D03*
X801998Y1471083D03*
X829852Y887022D03*
X829995Y920093D03*
X829494Y969724D03*
X835000Y756017D03*
X839000Y763017D03*
X835000Y774017D03*
X839000Y781017D03*
X835000Y792017D03*
X839000Y799017D03*
X835000Y810017D03*
X839000Y817017D03*
X836644Y858029D03*
X840381Y920586D03*
X844381D03*
X833898Y1448935D03*
X880054Y758201D03*
X874851D03*
X880054Y777215D03*
X874851Y777225D03*
X875916Y803407D03*
Y813557D03*
X879286Y908854D03*
X875286D03*
X894449Y600880D03*
X886610Y758200D03*
X885110Y777210D03*
X891916Y813557D03*
X895866Y820507D03*
X883866D03*
X888016D03*
X891916D03*
X883286Y908854D03*
X891286D03*
X887286D03*
X904393Y564718D03*
X908517D03*
X898815D03*
X909416Y813557D03*
X899916Y803407D03*
X899286Y908854D03*
X924143Y354908D03*
X918948Y354837D03*
X921790Y813557D03*
X913716Y803407D03*
X927286Y908854D03*
X923286D03*
X919286D03*
X915286D03*
X935124Y834473D03*
X941987Y854149D03*
X934944Y882078D03*
X931286Y908854D03*
X935286D03*
X952957Y919999D03*
X971648Y1221149D03*
X992000Y783517D03*
X985324Y1358823D03*
X999678Y327924D03*
X1021451Y317421D03*
X1025920Y317345D03*
X1013902Y890347D03*
X1029673Y317421D03*
X1051527Y1442528D03*
X1059448Y1435443D03*
X1074212Y1135426D03*
X1070472D03*
X1134673Y536517D03*
X1138125Y1213969D03*
X1160197Y794427D03*
X1173697D03*
X1187431Y878830D03*
Y871330D03*
X1183431D03*
X1187151Y923551D03*
Y930551D03*
X1205617Y1184048D03*
X1314604Y1270782D03*
X1326601Y331249D03*
X1333725Y331198D03*
X1319999Y1270782D03*
X1335936D03*
X1325478D03*
X1330582D03*
X1338500Y918017D03*
X1346083Y1122768D03*
X1342218Y1122805D03*
X1346362Y1270782D03*
X1351673D03*
X1341226D03*
X1364500Y816517D03*
X1360000D03*
X1355500D03*
X1364765Y1007283D03*
Y1014283D03*
X1356856Y1270782D03*
X1367828D03*
X1362308D03*
X1382667Y816388D03*
X1378000Y816517D03*
X1369000D03*
X1374500Y918017D03*
X1374551Y1023716D03*
X1370551D03*
X1378559Y1023697D03*
X1372152Y1270749D03*
X1380936Y1262872D03*
X1386122Y1262928D03*
X1391272Y1262894D03*
X1396296Y1262892D03*
X1407954Y1122979D03*
X1411829Y1122956D03*
X1411184Y1265627D03*
X1401428Y1262892D03*
X1415181Y1265627D03*
X1406916D03*
X1419451Y1265571D03*
X1440411Y1265627D03*
X1444381D03*
X1436439Y1265652D03*
X1467556Y890391D03*
X1493500Y940017D03*
X1510500Y926017D03*
X1528357Y971608D03*
X1517424Y972186D03*
X1527559Y1135426D03*
X1535000Y930517D03*
Y952017D03*
X1531299Y1135426D03*
X1591760Y536517D03*
X1595212Y1213969D03*
X1662704Y1184048D03*
X1817766Y1202417D03*
G54D54*
X414519Y1250868D03*
Y1264254D03*
X512430Y1250868D03*
Y1264254D03*
X1328693Y1250868D03*
Y1264254D03*
X1427004Y1251360D03*
Y1264746D03*
G54D72*
X1187951Y959596D03*
Y976722D03*
X1196219Y959596D03*
Y976722D03*
G54D45*
X272635Y451628D03*
X729721D03*
X1186808D03*
X1643895D03*
G54D36*
X212460Y554847D03*
X669546D03*
X1126633D03*
X1583720D03*
G54D27*
X51043Y60709D03*
Y150197D03*
X153405Y60709D03*
Y150197D03*
X190325Y455492D03*
Y503760D03*
Y583957D03*
Y636752D03*
X255767Y60709D03*
Y150197D03*
X279360Y368760D03*
Y421555D03*
Y501752D03*
Y550020D03*
X358129Y60709D03*
Y150197D03*
X508130Y60709D03*
Y150197D03*
X610492Y60709D03*
Y150197D03*
X647411Y455492D03*
Y503760D03*
Y583957D03*
Y636752D03*
X712854Y60709D03*
Y150197D03*
X736446Y368760D03*
Y421555D03*
Y501752D03*
Y550020D03*
X815216Y60709D03*
Y150197D03*
X965216Y60709D03*
Y150197D03*
X1067578Y60709D03*
Y150197D03*
X1104498Y455492D03*
Y503760D03*
Y583957D03*
Y636752D03*
X1169940Y60709D03*
Y150197D03*
X1193533Y368760D03*
Y421555D03*
Y501752D03*
Y550020D03*
X1272302Y60709D03*
Y150197D03*
X1422303Y60709D03*
Y150197D03*
X1524665Y60709D03*
Y150197D03*
X1561585Y455492D03*
Y503760D03*
Y583957D03*
Y636752D03*
X1627027Y60709D03*
Y150197D03*
X1650620Y368760D03*
Y421555D03*
Y501752D03*
Y550020D03*
X1729389Y60709D03*
Y150197D03*
G54D19*
X18037Y1515478D03*
X21537D03*
X63981Y1215113D03*
X96443Y893358D03*
X156299Y1138393D03*
X160039D03*
X220500Y539484D03*
X221263Y635637D03*
X223952Y1216936D03*
X246695Y636173D03*
X291444Y1187015D03*
X408523Y1330128D03*
X404657Y1330152D03*
X395959Y1358035D03*
X400879Y1403302D03*
X395111Y1493965D03*
X409981Y1536970D03*
X404157D03*
X424016Y331124D03*
X425773Y1268456D03*
X418735Y1285548D03*
X414735D03*
X410152Y1408437D03*
X416357Y1401933D03*
X430959Y331073D03*
X431822Y1125816D03*
X427997Y1125801D03*
X441078Y1266694D03*
X436325D03*
X431661Y1268456D03*
X432485Y1322278D03*
X450591Y1010250D03*
Y1017250D03*
X456377Y1026683D03*
X456472Y1266801D03*
X451377Y1266781D03*
X446246Y1266726D03*
X460377Y1026683D03*
X464385Y1026664D03*
X461677Y1266823D03*
X466975D03*
X472592Y1266791D03*
X489121D03*
X478101D03*
X483503D03*
X505791Y720400D03*
X497357Y1125921D03*
X493532Y1125896D03*
X494901Y1268465D03*
X505728D03*
X500302D03*
X522939Y1268550D03*
X519131Y1268549D03*
X537023Y718226D03*
X528741Y815633D03*
X530453Y1268616D03*
X526725Y1268590D03*
X545741Y801633D03*
X552665Y847802D03*
X553383Y893358D03*
X570241Y806133D03*
Y827633D03*
X562231Y847780D03*
X577501Y819532D03*
X588001D03*
X577501Y826532D03*
X588001D03*
X613386Y1138393D03*
X617126D03*
X677586Y539484D03*
X681039Y1216936D03*
X748531Y1187015D03*
X780631Y1453144D03*
X787631Y1022396D03*
X791686D03*
X801082Y1454050D03*
X801998Y1474050D03*
X829852Y889989D03*
X829995Y923060D03*
X829494Y972691D03*
X835000Y758984D03*
X839000Y765984D03*
X835000Y776984D03*
Y794984D03*
X839000Y783984D03*
X835000Y812984D03*
X839000Y801984D03*
Y819984D03*
X836644Y860996D03*
X840381Y923553D03*
X844381D03*
X833898Y1451902D03*
X880054Y761168D03*
X874851D03*
X880054Y780182D03*
X874851Y780192D03*
X875916Y806374D03*
Y816524D03*
X879286Y911821D03*
X875286D03*
X894449Y603847D03*
X886610Y761167D03*
X885110Y780177D03*
X891916Y816524D03*
X895866Y823474D03*
X883866D03*
X888016D03*
X891916D03*
X883286Y911821D03*
X891286D03*
X887286D03*
X904393Y567685D03*
X908517D03*
X898815D03*
X899916Y806374D03*
X909416Y816524D03*
X899286Y911821D03*
X924143Y357875D03*
X918948Y357804D03*
X913716Y806374D03*
X921790Y816524D03*
X927286Y911821D03*
X923286D03*
X919286D03*
X915286D03*
X935124Y837440D03*
X941987Y857116D03*
X934944Y885045D03*
X931286Y911821D03*
X935286D03*
X952957Y922966D03*
X971648Y1224116D03*
X992000Y786484D03*
X985324Y1361790D03*
X999678Y330891D03*
X1021451Y320388D03*
X1025920Y320312D03*
X1013902Y893314D03*
X1029673Y320388D03*
X1051527Y1445495D03*
X1059448Y1438410D03*
X1074212Y1138393D03*
X1070472D03*
X1134673Y539484D03*
X1138125Y1216936D03*
X1160197Y797394D03*
X1173697D03*
X1187431Y874297D03*
X1183431D03*
X1187431Y881797D03*
X1187151Y926518D03*
Y933518D03*
X1205617Y1187015D03*
X1314604Y1273749D03*
X1326601Y334216D03*
X1333725Y334165D03*
X1319999Y1273749D03*
X1335936D03*
X1325478D03*
X1330582D03*
X1338500Y920984D03*
X1346083Y1125735D03*
X1342218Y1125772D03*
X1346362Y1273749D03*
X1351673D03*
X1341226D03*
X1364500Y819484D03*
X1360000D03*
X1355500D03*
X1364765Y1010250D03*
Y1017250D03*
X1356856Y1273749D03*
X1367828D03*
X1362308D03*
X1382667Y819355D03*
X1378000Y819484D03*
X1369000D03*
X1374500Y920984D03*
X1374551Y1026683D03*
X1370551D03*
X1378559Y1026664D03*
X1380936Y1265839D03*
X1372152Y1273716D03*
X1386122Y1265895D03*
X1391272Y1265861D03*
X1396296Y1265859D03*
X1407954Y1125946D03*
X1411829Y1125923D03*
X1411184Y1268594D03*
X1401428Y1265859D03*
X1415181Y1268594D03*
X1406916D03*
X1419451Y1268538D03*
X1440411Y1268594D03*
X1444381D03*
X1436439Y1268619D03*
X1467556Y893358D03*
X1493500Y942984D03*
X1510500Y928984D03*
X1528357Y974575D03*
X1517424Y975153D03*
X1527559Y1138393D03*
X1535000Y933484D03*
Y954984D03*
X1531299Y1138393D03*
X1591760Y539484D03*
X1595212Y1216936D03*
X1662704Y1187015D03*
X1817766Y1205384D03*
G54D73*
X1190805Y959596D03*
X1193365D03*
X1190805Y976722D03*
X1193365D03*
G54D46*
X372028Y1534029D03*
G54D55*
X490050Y804497D03*
Y800757D03*
Y808237D03*
X501074Y800757D03*
Y804497D03*
Y808237D03*
X1465833Y928108D03*
X1454809D03*
Y931848D03*
Y935588D03*
X1465833Y931848D03*
Y935588D03*
G54D28*
X44079Y1529376D03*
Y1536376D03*
X394175Y1399389D03*
Y1406389D03*
X410955Y318485D03*
Y325485D03*
X405121Y930778D03*
X397121D03*
X405121Y937778D03*
X397121D03*
X411095Y1102897D03*
Y1109897D03*
X405231Y1124747D03*
Y1117747D03*
X423750Y538080D03*
Y545080D03*
X413121Y930778D03*
X421121D03*
X413121Y937778D03*
X421121D03*
X413231Y1124747D03*
Y1117747D03*
X426934Y1198971D03*
Y1191971D03*
X413469Y1198971D03*
Y1191971D03*
X435804Y538090D03*
Y545090D03*
X443223Y1102897D03*
Y1109897D03*
X437359Y1124747D03*
Y1117747D03*
X432975Y1152039D03*
Y1159039D03*
X434266Y1378453D03*
Y1371453D03*
X459104Y537990D03*
X447614Y538080D03*
X459104Y544990D03*
X447614Y545080D03*
X445359Y1124747D03*
Y1117747D03*
X470818Y1124747D03*
Y1117747D03*
X476682Y1102897D03*
X478818Y1124747D03*
Y1117747D03*
X476682Y1109897D03*
X486671Y1198971D03*
Y1191971D03*
X508810Y1102897D03*
Y1109897D03*
X502946Y1124747D03*
Y1117747D03*
X498562Y1152039D03*
Y1159039D03*
X500136Y1198971D03*
Y1191971D03*
X510946Y1124747D03*
Y1117747D03*
X1313540Y321577D03*
Y328577D03*
X1319405Y1124747D03*
Y1117747D03*
X1325269Y1102897D03*
Y1109897D03*
X1327405Y1124747D03*
Y1117747D03*
X1327643Y1198971D03*
Y1191971D03*
X1351533Y1124747D03*
Y1117747D03*
X1347149Y1152039D03*
Y1159039D03*
X1341108Y1198971D03*
Y1191971D03*
X1357397Y1102897D03*
Y1109897D03*
X1359533Y1124747D03*
Y1117747D03*
X1384992Y1124747D03*
Y1117747D03*
X1390856Y1102897D03*
Y1109897D03*
X1392992Y1124747D03*
Y1117747D03*
X1400845Y1198971D03*
Y1191971D03*
X1417120Y1124747D03*
Y1117747D03*
X1412736Y1152039D03*
Y1159039D03*
X1414310Y1198971D03*
Y1191971D03*
X1422984Y1102897D03*
Y1109897D03*
X1425120Y1124747D03*
Y1117747D03*
G54D37*
X212460Y551894D03*
Y557800D03*
X219546Y551894D03*
Y557800D03*
X669546Y551894D03*
Y557800D03*
X676632Y551894D03*
Y557800D03*
X1133719Y551894D03*
X1126633D03*
Y557800D03*
X1133719D03*
X1590806Y551894D03*
X1583720D03*
Y557800D03*
X1590806D03*
G54D64*
X904991Y843717D03*
Y846867D03*
X908140Y843717D03*
Y846867D03*
X901841Y843717D03*
Y846867D03*
Y872063D03*
Y875213D03*
X904991Y872063D03*
Y875213D03*
X908140Y872063D03*
Y875213D03*
X898692Y872063D03*
Y875213D03*
X941768Y864903D03*
Y868053D03*
X1331078Y834594D03*
Y837744D03*
X1334228Y850342D03*
Y853492D03*
X1337378Y859792D03*
Y862942D03*
Y853492D03*
Y856642D03*
X1349974Y866090D03*
Y869240D03*
X1346825Y866090D03*
Y869240D03*
X1340527Y866090D03*
Y869240D03*
X1343676Y866090D03*
Y869240D03*
X1340527Y872390D03*
Y875540D03*
X1343676Y872390D03*
Y875540D03*
X1346825Y872390D03*
Y875540D03*
X1349974Y872390D03*
Y875540D03*
X1362574Y837744D03*
Y840894D03*
Y853492D03*
Y856642D03*
X1356273Y866090D03*
Y869240D03*
X1359423Y866090D03*
Y869240D03*
Y872389D03*
Y875539D03*
X1356273Y872390D03*
Y875540D03*
X1353123Y866090D03*
Y869240D03*
Y872390D03*
Y875540D03*
G54D47*
X391691Y1321645D03*
X399171D03*
X897709Y545863D03*
X905189D03*
X1042180Y350954D03*
X1046180Y310454D03*
X1053660D03*
X1049660Y350954D03*
G54D56*
X501267Y830468D03*
Y833027D03*
Y835586D03*
X507821Y846830D03*
X499947D03*
X507821Y844271D03*
X499947D03*
X507821Y849389D03*
X499947D03*
X509141Y830468D03*
Y833027D03*
Y835586D03*
X1466026Y960378D03*
Y957819D03*
Y962937D03*
X1464706Y974181D03*
Y976740D03*
Y971622D03*
X1473900Y960378D03*
Y957819D03*
Y962937D03*
X1472580Y974181D03*
Y976740D03*
Y971622D03*
X1506626Y876339D03*
X1514500D03*
X1506626Y873780D03*
X1514500D03*
X1506626Y878898D03*
X1514500D03*
G54D74*
X1269749Y937697D03*
X1276049Y935138D03*
Y940256D03*
G54D29*
X65265Y822718D03*
X68869Y876608D03*
X56903Y905500D03*
Y901500D03*
X75981Y874859D03*
X85697Y664443D03*
X193616Y594400D03*
Y602400D03*
Y598400D03*
Y606400D03*
Y610400D03*
Y614400D03*
X216241Y623398D03*
X241025Y427029D03*
Y435029D03*
Y431029D03*
X274516Y388000D03*
Y384500D03*
X268879Y442606D03*
Y446606D03*
X270186Y463479D03*
X279171Y463235D03*
X281016Y388000D03*
X286987Y455152D03*
Y451152D03*
X388793Y1392591D03*
X388498Y1485778D03*
X387891Y1482239D03*
X400155Y1297965D03*
X395020Y1307238D03*
X401524Y1313443D03*
X395494Y1497835D03*
X422224Y1366972D03*
X413400Y1541221D03*
Y1547198D03*
X435850Y333907D03*
X436180Y342874D03*
X435068Y349675D03*
X429788Y1389026D03*
Y1385026D03*
X455714Y1197471D03*
X445422Y1293045D03*
X461717Y644087D03*
X468388Y1193471D03*
X488009Y791025D03*
X504157Y697405D03*
X503402Y712755D03*
Y708755D03*
X493450Y1024165D03*
X493438Y1028165D03*
X522240Y671119D03*
X514773Y831662D03*
X513843Y901500D03*
Y905500D03*
X525999Y600790D03*
X534257Y792649D03*
X525809Y876608D03*
X532921Y874859D03*
X541220Y830889D03*
Y835389D03*
X582319Y936807D03*
X650702Y594400D03*
Y602400D03*
Y598400D03*
Y606400D03*
Y610400D03*
Y614400D03*
X697035Y766471D03*
Y753471D03*
X697021Y771159D03*
Y784659D03*
X731602Y388000D03*
Y384500D03*
X727272Y463479D03*
X738102Y388000D03*
X744073Y455152D03*
Y451152D03*
X736257Y463235D03*
X780208Y1442282D03*
X780168Y1446194D03*
X796284Y1436240D03*
X813910Y869079D03*
X809983Y915705D03*
X815448Y920026D03*
X803150Y1429135D03*
X827637Y848986D03*
X827094Y880390D03*
X818513Y893885D03*
X822864Y921393D03*
X846864Y827419D03*
X840780Y847531D03*
X840253Y863413D03*
X840300Y871459D03*
X840253Y867413D03*
X841160Y1454159D03*
X853775Y863459D03*
Y859459D03*
Y871459D03*
Y879459D03*
Y867459D03*
X853766Y875468D03*
X864346Y869142D03*
X862765Y878942D03*
X853809Y892738D03*
X853806Y887707D03*
X853775Y883459D03*
X883760Y1456859D03*
X900965Y556363D03*
X911515Y578394D03*
X911465Y582863D03*
X911515Y586616D03*
X900683Y892455D03*
X900667Y884516D03*
X927712Y360129D03*
X927340Y366617D03*
X923296Y371739D03*
X914444Y817982D03*
X914344Y822083D03*
X934075Y1394627D03*
Y1398427D03*
Y1402227D03*
Y1406027D03*
X957449Y923116D03*
X971349Y901500D03*
Y905500D03*
X989975Y768775D03*
X982895Y876608D03*
X997723Y870398D03*
X1023935Y933822D03*
X1027311Y954222D03*
X1033822Y324752D03*
X1033801Y337736D03*
X1033868Y333519D03*
X1088806Y1537257D03*
X1107789Y594400D03*
Y602400D03*
Y598400D03*
Y606400D03*
Y610400D03*
Y614400D03*
X1098316Y1513398D03*
X1128691Y768859D03*
X1155198Y427029D03*
Y431029D03*
Y435029D03*
X1146001Y800642D03*
Y806642D03*
X1188689Y384500D03*
Y388000D03*
X1184359Y463479D03*
X1195189Y388000D03*
X1201160Y455152D03*
Y451152D03*
X1193344Y463235D03*
X1198235Y953789D03*
Y982789D03*
X1276233Y905173D03*
X1296516Y879800D03*
X1287980Y885651D03*
X1296516Y887800D03*
Y883800D03*
X1296970Y911478D03*
X1303016Y944000D03*
X1338435Y336999D03*
X1338765Y345966D03*
X1337653Y352767D03*
X1365716Y1422900D03*
X1382949Y561000D03*
Y607500D03*
X1382562Y1193471D03*
X1369888Y1197471D03*
X1402155Y961181D03*
X1407522Y1024254D03*
Y1028267D03*
X1428016Y905500D03*
Y901500D03*
X1442049Y601079D03*
X1439982Y876608D03*
X1447094Y874859D03*
X1440516Y931500D03*
Y936000D03*
X1479532Y959013D03*
X1491562Y327200D03*
X1492016Y318000D03*
X1485079Y880839D03*
Y870339D03*
X1492079Y880839D03*
Y870339D03*
X1499016Y920000D03*
X1505979Y958240D03*
Y962740D03*
X1564876Y602400D03*
Y598400D03*
Y594400D03*
Y606400D03*
Y610400D03*
Y614400D03*
X1612285Y427029D03*
Y431029D03*
Y435029D03*
X1640139Y442606D03*
Y446606D03*
X1641446Y463479D03*
X1652276Y388000D03*
X1645776D03*
Y384500D03*
X1658247Y455152D03*
Y451152D03*
X1650431Y463235D03*
X1789490Y989590D03*
X1798579Y964660D03*
X1801955Y985060D03*
G54D65*
X911290Y846867D03*
Y853166D03*
Y859465D03*
Y865764D03*
Y868914D03*
X914440Y846867D03*
Y853166D03*
Y859465D03*
Y865764D03*
Y868914D03*
X1302770Y854824D03*
X1302776Y851193D03*
X1302883Y859088D03*
X1315311Y840921D03*
X1318461D03*
X1303195Y832247D03*
X1306345D03*
X1303183Y835985D03*
X1306333D03*
X1305920Y854824D03*
X1305926Y851193D03*
X1306033Y859088D03*
X1315330Y884988D03*
X1318480D03*
X1337377Y878689D03*
X1340527D03*
X1346826Y891288D03*
X1349976D03*
G54D38*
X208035Y1516515D03*
X1460832Y763285D03*
X1459752Y806881D03*
X1626782Y659526D03*
X1763546Y802817D03*
G54D66*
X901841Y856316D03*
Y853166D03*
X927438Y856316D03*
Y853166D03*
X923888Y856316D03*
Y853166D03*
X920739Y862615D03*
Y859465D03*
X930768Y856316D03*
Y853166D03*
X934268Y856316D03*
Y853166D03*
X1314560Y864182D03*
Y867332D03*
X1306387Y896580D03*
Y893430D03*
X1310482Y896580D03*
Y893430D03*
X1334228Y878690D03*
Y875540D03*
Y894438D03*
Y891288D03*
X1346827Y856642D03*
Y853492D03*
X1349977Y856642D03*
Y853492D03*
X1343678Y856642D03*
Y853492D03*
X1340528Y856642D03*
Y853492D03*
X1349977Y862942D03*
Y859792D03*
X1340528Y862942D03*
Y859792D03*
X1346826Y862942D03*
Y859792D03*
X1343677Y862942D03*
Y859792D03*
X1337377Y869241D03*
Y866091D03*
Y875540D03*
Y872390D03*
X1356275Y862942D03*
Y859792D03*
X1359425Y862942D03*
Y859792D03*
X1356275Y856642D03*
Y853492D03*
X1359425Y856642D03*
Y853492D03*
X1353126Y856642D03*
Y853492D03*
Y862942D03*
Y859792D03*
X1362572Y875539D03*
Y872389D03*
X1365724Y894438D03*
Y891288D03*
X1372023Y869241D03*
Y866091D03*
G54D48*
X414519Y1251852D03*
Y1264254D03*
X512830Y1251852D03*
Y1264254D03*
X1328693Y1251852D03*
Y1264254D03*
X1427004Y1251852D03*
Y1264254D03*
G54D57*
X555682Y826212D03*
Y834086D03*
X558241Y826212D03*
X560800D03*
X558241Y834086D03*
X560800D03*
X583501Y797111D03*
X580942D03*
X586060D03*
X583501Y804985D03*
X580942D03*
X586060D03*
X1523000Y961437D03*
Y953563D03*
X1520441Y961437D03*
Y953563D03*
X1525559Y961437D03*
Y953563D03*
G54D75*
X1795453Y812874D03*
Y834922D03*
G54D39*
X228024Y602656D03*
Y607774D03*
Y605215D03*
X236686Y602656D03*
Y607774D03*
G54D76*
X1803917Y823898D03*
G54D58*
X798484Y980041D03*
Y1002089D03*
X801043Y980041D03*
X803602D03*
X806161D03*
X808720D03*
X811279D03*
X813839D03*
Y1002089D03*
X811279D03*
X808720D03*
X806161D03*
X803602D03*
X801043D03*
X816398Y980041D03*
X818957D03*
X821516D03*
X824075D03*
X826634D03*
Y1002089D03*
X824075D03*
X821516D03*
X818957D03*
X816398D03*
G54D49*
X409211Y1300396D03*
Y1298427D03*
Y1302364D03*
Y1312207D03*
Y1306301D03*
Y1310238D03*
Y1308270D03*
Y1304333D03*
X398881Y1383912D03*
Y1381943D03*
Y1379975D03*
Y1378006D03*
Y1391786D03*
Y1389817D03*
Y1387849D03*
Y1385880D03*
X417581Y1383912D03*
Y1381943D03*
Y1379975D03*
Y1378006D03*
Y1391786D03*
Y1389817D03*
Y1387849D03*
Y1385880D03*
X427911Y1302364D03*
Y1300396D03*
Y1298427D03*
Y1312207D03*
Y1304333D03*
Y1310238D03*
Y1306301D03*
Y1308270D03*
G54D67*
X1030635Y754546D03*
Y764546D03*
Y774546D03*
Y784546D03*
Y794546D03*
Y804546D03*
Y814546D03*
G54D77*
G01X-20602Y-468335D02*
Y-543335D01*
X479398D01*
Y-468335D01*
X-20602D01*
G01X-8602Y-533335D02*
Y-538335D01*
G01X-10059Y-533335D02*
X-7145D01*
G01X-2235Y-538335D02*
X-4769D01*
Y-533335D01*
X-2235D01*
G01X-3249Y-535752D02*
X-4769D01*
G01X331Y-533335D02*
Y-538335D01*
X2865D01*
G01X6698Y-538502D02*
X6571Y-538418D01*
Y-538252D01*
X6698Y-538168D01*
X6825Y-538252D01*
Y-538418D01*
X6698Y-538502D01*
G01Y-536252D02*
X6571Y-536168D01*
Y-536002D01*
X6698Y-535918D01*
X6825Y-536002D01*
Y-536168D01*
X6698Y-536252D01*
G01X11481Y-540002D02*
X10848Y-539168D01*
X10531Y-538335D01*
Y-535002D01*
X10848Y-534168D01*
X11481Y-533335D01*
G01X16898D02*
X16391Y-533502D01*
X16011Y-533918D01*
X15758Y-534418D01*
X15568Y-535085D01*
X15505Y-535835D01*
X15568Y-536585D01*
X15758Y-537252D01*
X16011Y-537752D01*
X16391Y-538168D01*
X16898Y-538335D01*
X17405Y-538168D01*
X17785Y-537752D01*
X18038Y-537252D01*
X18228Y-536585D01*
X18291Y-535835D01*
X18228Y-535085D01*
X18038Y-534418D01*
X17785Y-533918D01*
X17405Y-533502D01*
X16898Y-533335D01*
G01X20605Y-537335D02*
X20985Y-537918D01*
X21491Y-538252D01*
X22061Y-538335D01*
X22568Y-538252D01*
X23075Y-537835D01*
X23391Y-537335D01*
X23455Y-536835D01*
X23328Y-536252D01*
X22885Y-535835D01*
X22441Y-535668D01*
X21871D01*
G01X22441D02*
X22821Y-535418D01*
X23138Y-535002D01*
X23265Y-534502D01*
X23138Y-534002D01*
X22821Y-533585D01*
X22251Y-533335D01*
X21681Y-533418D01*
X21111Y-533752D01*
G01X27415Y-540002D02*
X28048Y-539168D01*
X28365Y-538335D01*
Y-535002D01*
X28048Y-534168D01*
X27415Y-533335D01*
G01X30805Y-537335D02*
X31185Y-537918D01*
X31691Y-538252D01*
X32261Y-538335D01*
X32768Y-538252D01*
X33275Y-537835D01*
X33591Y-537335D01*
X33655Y-536835D01*
X33528Y-536252D01*
X33085Y-535835D01*
X32641Y-535668D01*
X32071D01*
G01X32641D02*
X33021Y-535418D01*
X33338Y-535002D01*
X33465Y-534502D01*
X33338Y-534002D01*
X33021Y-533585D01*
X32451Y-533335D01*
X31881Y-533418D01*
X31311Y-533752D01*
G01X36095Y-534168D02*
X36475Y-533668D01*
X36918Y-533418D01*
X37425Y-533335D01*
X38058Y-533502D01*
X38501Y-533918D01*
X38628Y-534418D01*
X38565Y-534918D01*
X38311Y-535335D01*
X37045Y-536168D01*
X36475Y-536752D01*
X36095Y-537585D01*
X35968Y-538335D01*
X38628D01*
G01X42271D02*
X42398Y-537252D01*
X42588Y-536335D01*
X42841Y-535502D01*
X43158Y-534585D01*
X43665Y-533335D01*
X41131D01*
G01X46675Y-536668D02*
X48321D01*
G01X51395Y-534168D02*
X51775Y-533668D01*
X52218Y-533418D01*
X52725Y-533335D01*
X53358Y-533502D01*
X53801Y-533918D01*
X53928Y-534418D01*
X53865Y-534918D01*
X53611Y-535335D01*
X52345Y-536168D01*
X51775Y-536752D01*
X51395Y-537585D01*
X51268Y-538335D01*
X53928D01*
G01X56305Y-537335D02*
X56685Y-537918D01*
X57191Y-538252D01*
X57761Y-538335D01*
X58268Y-538252D01*
X58775Y-537835D01*
X59091Y-537335D01*
X59155Y-536835D01*
X59028Y-536252D01*
X58585Y-535835D01*
X58141Y-535668D01*
X57571D01*
G01X58141D02*
X58521Y-535418D01*
X58838Y-535002D01*
X58965Y-534502D01*
X58838Y-534002D01*
X58521Y-533585D01*
X57951Y-533335D01*
X57381Y-533418D01*
X56811Y-533752D01*
G01X63558Y-538335D02*
Y-533335D01*
X61215Y-536918D01*
X64381D01*
G01X66505Y-537585D02*
X66885Y-538002D01*
X67328Y-538252D01*
X67898Y-538335D01*
X68468Y-538168D01*
X68911Y-537835D01*
X69228Y-537252D01*
X69291Y-536585D01*
X69165Y-535918D01*
X68848Y-535502D01*
X68405Y-535168D01*
X67961Y-535085D01*
X67518Y-535168D01*
X66948Y-535502D01*
X67138Y-533335D01*
X68848D01*
G01X76895Y-538335D02*
Y-533335D01*
X79301D01*
G01X78415Y-535752D02*
X76895D01*
G01X81615Y-538335D02*
X83198Y-533335D01*
X84781Y-538335D01*
G01X84211Y-536585D02*
X82185D01*
G01X86968Y-538335D02*
X89628Y-533335D01*
G01X86968D02*
X89628Y-538335D01*
G01X93398Y-538502D02*
X93271Y-538418D01*
Y-538252D01*
X93398Y-538168D01*
X93525Y-538252D01*
Y-538418D01*
X93398Y-538502D01*
G01Y-536252D02*
X93271Y-536168D01*
Y-536002D01*
X93398Y-535918D01*
X93525Y-536002D01*
Y-536168D01*
X93398Y-536252D01*
G01X98181Y-540002D02*
X97548Y-539168D01*
X97231Y-538335D01*
Y-535002D01*
X97548Y-534168D01*
X98181Y-533335D01*
G01X103598D02*
X103091Y-533502D01*
X102711Y-533918D01*
X102458Y-534418D01*
X102268Y-535085D01*
X102205Y-535835D01*
X102268Y-536585D01*
X102458Y-537252D01*
X102711Y-537752D01*
X103091Y-538168D01*
X103598Y-538335D01*
X104105Y-538168D01*
X104485Y-537752D01*
X104738Y-537252D01*
X104928Y-536585D01*
X104991Y-535835D01*
X104928Y-535085D01*
X104738Y-534418D01*
X104485Y-533918D01*
X104105Y-533502D01*
X103598Y-533335D01*
G01X107305Y-537335D02*
X107685Y-537918D01*
X108191Y-538252D01*
X108761Y-538335D01*
X109268Y-538252D01*
X109775Y-537835D01*
X110091Y-537335D01*
X110155Y-536835D01*
X110028Y-536252D01*
X109585Y-535835D01*
X109141Y-535668D01*
X108571D01*
G01X109141D02*
X109521Y-535418D01*
X109838Y-535002D01*
X109965Y-534502D01*
X109838Y-534002D01*
X109521Y-533585D01*
X108951Y-533335D01*
X108381Y-533418D01*
X107811Y-533752D01*
G01X114115Y-540002D02*
X114748Y-539168D01*
X115065Y-538335D01*
Y-535002D01*
X114748Y-534168D01*
X114115Y-533335D01*
G01X117505Y-537335D02*
X117885Y-537918D01*
X118391Y-538252D01*
X118961Y-538335D01*
X119468Y-538252D01*
X119975Y-537835D01*
X120291Y-537335D01*
X120355Y-536835D01*
X120228Y-536252D01*
X119785Y-535835D01*
X119341Y-535668D01*
X118771D01*
G01X119341D02*
X119721Y-535418D01*
X120038Y-535002D01*
X120165Y-534502D01*
X120038Y-534002D01*
X119721Y-533585D01*
X119151Y-533335D01*
X118581Y-533418D01*
X118011Y-533752D01*
G01X122921Y-537752D02*
X123365Y-538168D01*
X123871Y-538335D01*
X124378Y-538168D01*
X124821Y-537668D01*
X125138Y-536918D01*
X125265Y-536168D01*
Y-535252D01*
X125138Y-534502D01*
X124821Y-533835D01*
X124441Y-533502D01*
X123998Y-533335D01*
X123491Y-533502D01*
X123111Y-533835D01*
X122858Y-534335D01*
X122731Y-535002D01*
X122858Y-535585D01*
X123175Y-536168D01*
X123555Y-536502D01*
X123998Y-536585D01*
X124505Y-536418D01*
X124885Y-536002D01*
X125265Y-535252D01*
G01X128971Y-538335D02*
X129098Y-537252D01*
X129288Y-536335D01*
X129541Y-535502D01*
X129858Y-534585D01*
X130365Y-533335D01*
X127831D01*
G01X133375Y-536668D02*
X135021D01*
G01X137905Y-537335D02*
X138285Y-537918D01*
X138791Y-538252D01*
X139361Y-538335D01*
X139868Y-538252D01*
X140375Y-537835D01*
X140691Y-537335D01*
X140755Y-536835D01*
X140628Y-536252D01*
X140185Y-535835D01*
X139741Y-535668D01*
X139171D01*
G01X139741D02*
X140121Y-535418D01*
X140438Y-535002D01*
X140565Y-534502D01*
X140438Y-534002D01*
X140121Y-533585D01*
X139551Y-533335D01*
X138981Y-533418D01*
X138411Y-533752D01*
G01X143195Y-536252D02*
X143638Y-535668D01*
X144018Y-535335D01*
X144525Y-535168D01*
X144968Y-535335D01*
X145285Y-535668D01*
X145538Y-536168D01*
X145601Y-536752D01*
X145538Y-537252D01*
X145285Y-537752D01*
X144905Y-538168D01*
X144461Y-538335D01*
X143955Y-538168D01*
X143511Y-537668D01*
X143258Y-536918D01*
X143195Y-536085D01*
X143321Y-535002D01*
X143511Y-534418D01*
X143828Y-533835D01*
X144271Y-533418D01*
X144715Y-533335D01*
X145158Y-533502D01*
X145475Y-533918D01*
G01X149498Y-538335D02*
Y-533335D01*
X148738Y-534335D01*
G01Y-538335D02*
X150258D01*
G01X155358D02*
Y-533335D01*
X153015Y-536918D01*
X156181D01*
G01X174398Y-468335D02*
Y-543335D01*
G01Y-518335D02*
X277398D01*
Y-493335D01*
G01X174398D02*
X277398D01*
G01Y-468335D02*
Y-543335D01*
G01X279398Y-468335D02*
Y-543335D01*
G01X284905Y-528335D02*
Y-523335D01*
X286171D01*
X286678Y-523585D01*
X287058Y-523918D01*
X287375Y-524418D01*
X287628Y-525002D01*
X287691Y-525835D01*
X287628Y-526668D01*
X287375Y-527252D01*
X287058Y-527752D01*
X286678Y-528085D01*
X286171Y-528335D01*
X284905D01*
G01X289815D02*
X291398Y-523335D01*
X292981Y-528335D01*
G01X292411Y-526585D02*
X290385D01*
G01X296498Y-523335D02*
Y-528335D01*
G01X295041Y-523335D02*
X297955D01*
G01X302865Y-528335D02*
X300331D01*
Y-523335D01*
X302865D01*
G01X301851Y-525752D02*
X300331D01*
G01X306698Y-528502D02*
X306571Y-528418D01*
Y-528252D01*
X306698Y-528168D01*
X306825Y-528252D01*
Y-528418D01*
X306698Y-528502D01*
G01Y-526252D02*
X306571Y-526168D01*
Y-526002D01*
X306698Y-525918D01*
X306825Y-526002D01*
Y-526168D01*
X306698Y-526252D01*
G01X279398Y-518335D02*
X479398D01*
G01X285031Y-503335D02*
Y-498335D01*
X286551D01*
X287058Y-498585D01*
X287438Y-499168D01*
X287565Y-499835D01*
X287438Y-500502D01*
X287121Y-501002D01*
X286551Y-501252D01*
X285031D01*
G01X290258Y-503502D02*
X292538Y-498335D01*
G01X295041Y-503335D02*
Y-498335D01*
X297955Y-503335D01*
Y-498335D01*
G01X301598Y-503502D02*
X301471Y-503418D01*
Y-503252D01*
X301598Y-503168D01*
X301725Y-503252D01*
Y-503418D01*
X301598Y-503502D01*
G01Y-501252D02*
X301471Y-501168D01*
Y-501002D01*
X301598Y-500918D01*
X301725Y-501002D01*
Y-501168D01*
X301598Y-501252D01*
G01X279398Y-493335D02*
X479398D01*
G01X285031Y-478335D02*
Y-473335D01*
X286551D01*
X287058Y-473585D01*
X287438Y-474168D01*
X287565Y-474835D01*
X287438Y-475502D01*
X287121Y-476002D01*
X286551Y-476252D01*
X285031D01*
G01X290131Y-478335D02*
Y-473335D01*
X291715D01*
X292221Y-473585D01*
X292538Y-473918D01*
X292665Y-474585D01*
X292538Y-475252D01*
X292158Y-475668D01*
X291715Y-475918D01*
X290131D01*
G01X291715D02*
X292665Y-478335D01*
G01X296498D02*
X295991Y-478252D01*
X295548Y-477918D01*
X295168Y-477418D01*
X294915Y-476835D01*
X294788Y-476168D01*
Y-475502D01*
X294915Y-474835D01*
X295168Y-474252D01*
X295548Y-473752D01*
X295991Y-473418D01*
X296498Y-473335D01*
X297005Y-473418D01*
X297448Y-473752D01*
X297828Y-474252D01*
X298081Y-474835D01*
X298208Y-475502D01*
Y-476168D01*
X298081Y-476835D01*
X297828Y-477418D01*
X297448Y-477918D01*
X297005Y-478252D01*
X296498Y-478335D01*
G01X300331Y-477335D02*
X300648Y-477835D01*
X301028Y-478168D01*
X301471Y-478335D01*
X301978Y-478168D01*
X302358Y-477835D01*
X302738Y-477335D01*
X302865Y-476668D01*
Y-473335D01*
G01X307965Y-478335D02*
X305431D01*
Y-473335D01*
X307965D01*
G01X306951Y-475752D02*
X305431D01*
G01X313191Y-473752D02*
X312811Y-473502D01*
X312368Y-473335D01*
X311861D01*
X311291Y-473585D01*
X310848Y-474002D01*
X310531Y-474502D01*
X310278Y-475335D01*
X310215Y-476085D01*
X310341Y-476835D01*
X310531Y-477335D01*
X310911Y-477835D01*
X311355Y-478168D01*
X311798Y-478335D01*
X312241D01*
X312685Y-478168D01*
X313065Y-477918D01*
X313381Y-477585D01*
G01X316898Y-473335D02*
Y-478335D01*
G01X315441Y-473335D02*
X318355D01*
G01X321998Y-478502D02*
X321871Y-478418D01*
Y-478252D01*
X321998Y-478168D01*
X322125Y-478252D01*
Y-478418D01*
X321998Y-478502D01*
G01Y-476252D02*
X321871Y-476168D01*
Y-476002D01*
X321998Y-475918D01*
X322125Y-476002D01*
Y-476168D01*
X321998Y-476252D01*
G01X394258Y-543563D02*
Y-518563D01*
G01X397031Y-520835D02*
Y-525835D01*
X399565D01*
G01X402638Y-520835D02*
X404158D01*
G01X403398D02*
Y-525835D01*
G01X402638D02*
X404158D01*
G01X409005Y-523168D02*
X409258Y-522918D01*
X409448Y-522502D01*
X409575Y-521918D01*
X409448Y-521418D01*
X409195Y-521085D01*
X408751Y-520835D01*
X407041D01*
Y-525835D01*
X409131D01*
X409575Y-525502D01*
X409828Y-525002D01*
X409955Y-524418D01*
X409828Y-523835D01*
X409448Y-523335D01*
X409005Y-523168D01*
X407041D01*
G01X413598Y-526002D02*
X413471Y-525918D01*
Y-525752D01*
X413598Y-525668D01*
X413725Y-525752D01*
Y-525918D01*
X413598Y-526002D01*
G01Y-523752D02*
X413471Y-523668D01*
Y-523502D01*
X413598Y-523418D01*
X413725Y-523502D01*
Y-523668D01*
X413598Y-523752D01*
G01X437258Y-518563D02*
Y-543563D01*
G01X437398Y-518335D02*
Y-543335D01*
G01X441298Y-520835D02*
Y-525835D01*
G01X439841Y-520835D02*
X442755D01*
G01X446398Y-525835D02*
X446018Y-525752D01*
X445638Y-525418D01*
X445385Y-524835D01*
X445258Y-524168D01*
X445385Y-523502D01*
X445638Y-522918D01*
X446018Y-522585D01*
X446398Y-522502D01*
X446778Y-522585D01*
X447158Y-522918D01*
X447411Y-523502D01*
X447475Y-524168D01*
X447411Y-524835D01*
X447158Y-525418D01*
X446778Y-525752D01*
X446398Y-525835D01*
G01X451498D02*
X451118Y-525752D01*
X450738Y-525418D01*
X450485Y-524835D01*
X450358Y-524168D01*
X450485Y-523502D01*
X450738Y-522918D01*
X451118Y-522585D01*
X451498Y-522502D01*
X451878Y-522585D01*
X452258Y-522918D01*
X452511Y-523502D01*
X452575Y-524168D01*
X452511Y-524835D01*
X452258Y-525418D01*
X451878Y-525752D01*
X451498Y-525835D01*
G01X456598D02*
Y-520835D01*
G01X461698Y-526002D02*
X461571Y-525918D01*
Y-525752D01*
X461698Y-525668D01*
X461825Y-525752D01*
Y-525918D01*
X461698Y-526002D01*
G01Y-523752D02*
X461571Y-523668D01*
Y-523502D01*
X461698Y-523418D01*
X461825Y-523502D01*
Y-523668D01*
X461698Y-523752D01*
G01X437398Y-493335D02*
Y-518335D01*
G01X440031Y-500835D02*
Y-495835D01*
X441615D01*
X442121Y-496085D01*
X442438Y-496418D01*
X442565Y-497085D01*
X442438Y-497752D01*
X442058Y-498168D01*
X441615Y-498418D01*
X440031D01*
G01X441615D02*
X442565Y-500835D01*
G01X447665D02*
X445131D01*
Y-495835D01*
X447665D01*
G01X446651Y-498252D02*
X445131D01*
G01X449915Y-495835D02*
X451498Y-500835D01*
X453081Y-495835D01*
G01X456598Y-501002D02*
X456471Y-500918D01*
Y-500752D01*
X456598Y-500668D01*
X456725Y-500752D01*
Y-500918D01*
X456598Y-501002D01*
G01Y-498752D02*
X456471Y-498668D01*
Y-498502D01*
X456598Y-498418D01*
X456725Y-498502D01*
Y-498668D01*
X456598Y-498752D01*
G01X445411Y-546502D02*
X445518Y-546377D01*
X445598Y-546168D01*
X445651Y-545877D01*
X445598Y-545627D01*
X445491Y-545460D01*
X445305Y-545335D01*
X444585D01*
Y-547835D01*
X445465D01*
X445651Y-547668D01*
X445758Y-547418D01*
X445811Y-547127D01*
X445758Y-546835D01*
X445598Y-546585D01*
X445411Y-546502D01*
X444585D01*
G01X447878Y-547835D02*
Y-546168D01*
G01Y-546460D02*
X447771Y-546293D01*
X447611Y-546210D01*
X447425Y-546168D01*
X447238Y-546252D01*
X447078Y-546418D01*
X446971Y-546668D01*
X446918Y-547002D01*
X446971Y-547335D01*
X447078Y-547585D01*
X447238Y-547752D01*
X447425Y-547835D01*
X447611Y-547793D01*
X447771Y-547668D01*
X447878Y-547502D01*
G01X449198Y-547543D02*
X449331Y-547710D01*
X449518Y-547835D01*
X449678D01*
X449838Y-547752D01*
X449945Y-547627D01*
X449998Y-547460D01*
X449971Y-547210D01*
X449865Y-547085D01*
X449385Y-546835D01*
X449278Y-546543D01*
X449331Y-546335D01*
X449438Y-546210D01*
X449598Y-546168D01*
X449758Y-546210D01*
X449918Y-546335D01*
G01X451398Y-546710D02*
X452251D01*
X452171Y-546418D01*
X452038Y-546252D01*
X451851Y-546168D01*
X451665Y-546210D01*
X451505Y-546335D01*
X451398Y-546627D01*
X451345Y-546877D01*
Y-547127D01*
X451398Y-547377D01*
X451531Y-547627D01*
X451691Y-547793D01*
X451878Y-547835D01*
X452065Y-547752D01*
X452251Y-547502D01*
G01X453518Y-547835D02*
Y-545335D01*
G01Y-546585D02*
X453651Y-546335D01*
X453811Y-546210D01*
X453971Y-546168D01*
X454211Y-546252D01*
X454371Y-546418D01*
X454478Y-546710D01*
Y-547043D01*
X454425Y-547377D01*
X454318Y-547627D01*
X454131Y-547793D01*
X453971Y-547835D01*
X453811Y-547793D01*
X453651Y-547668D01*
X453518Y-547460D01*
G01X456198Y-547835D02*
X456038Y-547793D01*
X455878Y-547627D01*
X455771Y-547335D01*
X455718Y-547002D01*
X455771Y-546668D01*
X455878Y-546377D01*
X456038Y-546210D01*
X456198Y-546168D01*
X456358Y-546210D01*
X456518Y-546377D01*
X456625Y-546668D01*
X456651Y-547002D01*
X456625Y-547335D01*
X456518Y-547627D01*
X456358Y-547793D01*
X456198Y-547835D01*
G01X458878D02*
Y-546168D01*
G01Y-546460D02*
X458771Y-546293D01*
X458611Y-546210D01*
X458425Y-546168D01*
X458238Y-546252D01*
X458078Y-546418D01*
X457971Y-546668D01*
X457918Y-547002D01*
X457971Y-547335D01*
X458078Y-547585D01*
X458238Y-547752D01*
X458425Y-547835D01*
X458611Y-547793D01*
X458771Y-547668D01*
X458878Y-547502D01*
G01X460225Y-547835D02*
Y-546168D01*
G01Y-546502D02*
X460358Y-546335D01*
X460491Y-546210D01*
X460678Y-546168D01*
X460811Y-546210D01*
X460971Y-546335D01*
G01X463278Y-545335D02*
Y-547835D01*
G01Y-547460D02*
X463171Y-547668D01*
X463011Y-547793D01*
X462825Y-547835D01*
X462611Y-547752D01*
X462451Y-547543D01*
X462345Y-547293D01*
X462318Y-547002D01*
X462345Y-546710D01*
X462451Y-546460D01*
X462611Y-546252D01*
X462825Y-546168D01*
X463011Y-546210D01*
X463145Y-546293D01*
X463278Y-546460D01*
G01X466665Y-547835D02*
Y-545335D01*
X467331D01*
X467545Y-545460D01*
X467678Y-545627D01*
X467731Y-545960D01*
X467678Y-546293D01*
X467518Y-546502D01*
X467331Y-546627D01*
X466665D01*
G01X467331D02*
X467731Y-547835D01*
G01X468998Y-546710D02*
X469851D01*
X469771Y-546418D01*
X469638Y-546252D01*
X469451Y-546168D01*
X469265Y-546210D01*
X469105Y-546335D01*
X468998Y-546627D01*
X468945Y-546877D01*
Y-547127D01*
X468998Y-547377D01*
X469131Y-547627D01*
X469291Y-547793D01*
X469478Y-547835D01*
X469665Y-547752D01*
X469851Y-547502D01*
G01X471118Y-546168D02*
X471598Y-547835D01*
X472078Y-546168D01*
G01X473798Y-547918D02*
X473745Y-547877D01*
Y-547793D01*
X473798Y-547752D01*
X473851Y-547793D01*
Y-547877D01*
X473798Y-547918D01*
G01X475545Y-547543D02*
X475731Y-547752D01*
X475945Y-547835D01*
X476158Y-547752D01*
X476345Y-547502D01*
X476478Y-547127D01*
X476531Y-546752D01*
Y-546293D01*
X476478Y-545918D01*
X476345Y-545585D01*
X476185Y-545418D01*
X475998Y-545335D01*
X475785Y-545418D01*
X475625Y-545585D01*
X475518Y-545835D01*
X475465Y-546168D01*
X475518Y-546460D01*
X475651Y-546752D01*
X475811Y-546918D01*
X475998Y-546960D01*
X476211Y-546877D01*
X476371Y-546668D01*
X476531Y-546293D01*
G01X478411Y-546502D02*
X478518Y-546377D01*
X478598Y-546168D01*
X478651Y-545877D01*
X478598Y-545627D01*
X478491Y-545460D01*
X478305Y-545335D01*
X477585D01*
Y-547835D01*
X478465D01*
X478651Y-547668D01*
X478758Y-547418D01*
X478811Y-547127D01*
X478758Y-546835D01*
X478598Y-546585D01*
X478411Y-546502D01*
X477585D01*
G01X-1490433Y-1677216D02*
Y3837819D01*
X4496476D01*
Y-1677216D01*
X-1490433D01*
G01X-7782Y-515685D02*
X-6215D01*
Y-517575D01*
X-6685Y-518205D01*
X-7234Y-518625D01*
X-8017Y-518835D01*
X-8800Y-518625D01*
X-9349Y-518205D01*
X-9819Y-517575D01*
X-10132Y-516840D01*
X-10289Y-516000D01*
Y-515265D01*
X-10132Y-514635D01*
X-9819Y-513900D01*
X-9349Y-513270D01*
X-8879Y-512850D01*
X-8252Y-512535D01*
X-7704D01*
X-7077Y-512745D01*
X-6607Y-513165D01*
G01X-3675Y-512535D02*
Y-517050D01*
X-3362Y-517995D01*
X-2735Y-518625D01*
X-1952Y-518835D01*
X-1169Y-518625D01*
X-542Y-517995D01*
X-229Y-517050D01*
Y-512535D01*
G01X3408D02*
X5288D01*
G01X4348D02*
Y-518835D01*
G01X3408D02*
X5288D01*
G01X9003Y-517995D02*
X9630Y-518520D01*
X10335Y-518835D01*
X10961D01*
X11588Y-518520D01*
X12058Y-517995D01*
X12293Y-517260D01*
X12136Y-516525D01*
X11745Y-515895D01*
X11040Y-515475D01*
X10100Y-515265D01*
X9551Y-514845D01*
X9316Y-514110D01*
X9473Y-513375D01*
X9865Y-512850D01*
X10413Y-512535D01*
X10961D01*
X11510Y-512745D01*
X11980Y-513270D01*
G01X15303Y-518835D02*
Y-512535D01*
G01X18593D02*
Y-518835D01*
G01Y-515685D02*
X15303D01*
G01X21290Y-518835D02*
X23248Y-512535D01*
X25206Y-518835D01*
G01X24501Y-516630D02*
X21995D01*
G01X27746Y-518835D02*
Y-512535D01*
X31350Y-518835D01*
Y-512535D01*
G01X40425Y-518835D02*
Y-512535D01*
X41991D01*
X42618Y-512850D01*
X43088Y-513270D01*
X43480Y-513900D01*
X43793Y-514635D01*
X43871Y-515685D01*
X43793Y-516735D01*
X43480Y-517470D01*
X43088Y-518100D01*
X42618Y-518520D01*
X41991Y-518835D01*
X40425D01*
G01X47508Y-512535D02*
X49388D01*
G01X48448D02*
Y-518835D01*
G01X47508D02*
X49388D01*
G01X53103Y-517995D02*
X53730Y-518520D01*
X54435Y-518835D01*
X55061D01*
X55688Y-518520D01*
X56158Y-517995D01*
X56393Y-517260D01*
X56236Y-516525D01*
X55845Y-515895D01*
X55140Y-515475D01*
X54200Y-515265D01*
X53651Y-514845D01*
X53416Y-514110D01*
X53573Y-513375D01*
X53965Y-512850D01*
X54513Y-512535D01*
X55061D01*
X55610Y-512745D01*
X56080Y-513270D01*
G01X61048Y-512535D02*
Y-518835D01*
G01X59246Y-512535D02*
X62850D01*
G01X67348Y-519045D02*
X67191Y-518940D01*
Y-518730D01*
X67348Y-518625D01*
X67505Y-518730D01*
Y-518940D01*
X67348Y-519045D01*
G01X73491Y-519990D02*
X73805Y-518625D01*
G01X79948Y-512535D02*
Y-518835D01*
G01X78146Y-512535D02*
X81750D01*
G01X84290Y-518835D02*
X86248Y-512535D01*
X88206Y-518835D01*
G01X87501Y-516630D02*
X84995D01*
G01X92548Y-518835D02*
X91921Y-518730D01*
X91373Y-518310D01*
X90903Y-517680D01*
X90590Y-516945D01*
X90433Y-516105D01*
Y-515265D01*
X90590Y-514425D01*
X90903Y-513690D01*
X91373Y-513060D01*
X91921Y-512640D01*
X92548Y-512535D01*
X93175Y-512640D01*
X93723Y-513060D01*
X94193Y-513690D01*
X94506Y-514425D01*
X94663Y-515265D01*
Y-516105D01*
X94506Y-516945D01*
X94193Y-517680D01*
X93723Y-518310D01*
X93175Y-518730D01*
X92548Y-518835D01*
G01X98848D02*
Y-516000D01*
X97281Y-512535D01*
G01X100415D02*
X98848Y-516000D01*
G01X103425Y-512535D02*
Y-517050D01*
X103738Y-517995D01*
X104365Y-518625D01*
X105148Y-518835D01*
X105931Y-518625D01*
X106558Y-517995D01*
X106871Y-517050D01*
Y-512535D01*
G01X109490Y-518835D02*
X111448Y-512535D01*
X113406Y-518835D01*
G01X112701Y-516630D02*
X110195D01*
G01X115946Y-518835D02*
Y-512535D01*
X119550Y-518835D01*
Y-512535D01*
G01X-6529Y-523060D02*
X-6999Y-522745D01*
X-7547Y-522535D01*
X-8174D01*
X-8879Y-522850D01*
X-9427Y-523375D01*
X-9819Y-524005D01*
X-10132Y-525055D01*
X-10210Y-526000D01*
X-10054Y-526945D01*
X-9819Y-527575D01*
X-9349Y-528205D01*
X-8800Y-528625D01*
X-8252Y-528835D01*
X-7704D01*
X-7155Y-528625D01*
X-6685Y-528310D01*
X-6294Y-527890D01*
G01X-2892Y-522535D02*
X-1012D01*
G01X-1952D02*
Y-528835D01*
G01X-2892D02*
X-1012D01*
G01X4348Y-522535D02*
Y-528835D01*
G01X2546Y-522535D02*
X6150D01*
G01X10648Y-528835D02*
Y-526000D01*
X9081Y-522535D01*
G01X12215D02*
X10648Y-526000D01*
G01X21525Y-527575D02*
X21995Y-528310D01*
X22621Y-528730D01*
X23326Y-528835D01*
X23953Y-528730D01*
X24580Y-528205D01*
X24971Y-527575D01*
X25050Y-526945D01*
X24893Y-526210D01*
X24345Y-525685D01*
X23796Y-525475D01*
X23091D01*
G01X23796D02*
X24266Y-525160D01*
X24658Y-524635D01*
X24815Y-524005D01*
X24658Y-523375D01*
X24266Y-522850D01*
X23561Y-522535D01*
X22856Y-522640D01*
X22151Y-523060D01*
G01X27825Y-527575D02*
X28295Y-528310D01*
X28921Y-528730D01*
X29626Y-528835D01*
X30253Y-528730D01*
X30880Y-528205D01*
X31271Y-527575D01*
X31350Y-526945D01*
X31193Y-526210D01*
X30645Y-525685D01*
X30096Y-525475D01*
X29391D01*
G01X30096D02*
X30566Y-525160D01*
X30958Y-524635D01*
X31115Y-524005D01*
X30958Y-523375D01*
X30566Y-522850D01*
X29861Y-522535D01*
X29156Y-522640D01*
X28451Y-523060D01*
G01X34125Y-527575D02*
X34595Y-528310D01*
X35221Y-528730D01*
X35926Y-528835D01*
X36553Y-528730D01*
X37180Y-528205D01*
X37571Y-527575D01*
X37650Y-526945D01*
X37493Y-526210D01*
X36945Y-525685D01*
X36396Y-525475D01*
X35691D01*
G01X36396D02*
X36866Y-525160D01*
X37258Y-524635D01*
X37415Y-524005D01*
X37258Y-523375D01*
X36866Y-522850D01*
X36161Y-522535D01*
X35456Y-522640D01*
X34751Y-523060D01*
G01X41991Y-528835D02*
X42148Y-527470D01*
X42383Y-526315D01*
X42696Y-525265D01*
X43088Y-524110D01*
X43715Y-522535D01*
X40581D01*
G01X48291Y-528835D02*
X48448Y-527470D01*
X48683Y-526315D01*
X48996Y-525265D01*
X49388Y-524110D01*
X50015Y-522535D01*
X46881D01*
G01X54591Y-529990D02*
X54905Y-528625D01*
G01X61048Y-522535D02*
Y-528835D01*
G01X59246Y-522535D02*
X62850D01*
G01X65390Y-528835D02*
X67348Y-522535D01*
X69306Y-528835D01*
G01X68601Y-526630D02*
X66095D01*
G01X72708Y-522535D02*
X74588D01*
G01X73648D02*
Y-528835D01*
G01X72708D02*
X74588D01*
G01X77598Y-522535D02*
X78695Y-528835D01*
X79948Y-522535D01*
X81201Y-528835D01*
X82298Y-522535D01*
G01X84290Y-528835D02*
X86248Y-522535D01*
X88206Y-528835D01*
G01X87501Y-526630D02*
X84995D01*
G01X90746Y-528835D02*
Y-522535D01*
X94350Y-528835D01*
Y-522535D01*
G01X104756Y-530935D02*
X103973Y-529885D01*
X103581Y-528835D01*
Y-524635D01*
X103973Y-523585D01*
X104756Y-522535D01*
G01X116181Y-528835D02*
Y-522535D01*
X118140D01*
X118766Y-522850D01*
X119158Y-523270D01*
X119315Y-524110D01*
X119158Y-524950D01*
X118688Y-525475D01*
X118140Y-525790D01*
X116181D01*
G01X118140D02*
X119315Y-528835D01*
G01X124048Y-529045D02*
X123891Y-528940D01*
Y-528730D01*
X124048Y-528625D01*
X124205Y-528730D01*
Y-528940D01*
X124048Y-529045D01*
G01X130348Y-528835D02*
X129721Y-528730D01*
X129173Y-528310D01*
X128703Y-527680D01*
X128390Y-526945D01*
X128233Y-526105D01*
Y-525265D01*
X128390Y-524425D01*
X128703Y-523690D01*
X129173Y-523060D01*
X129721Y-522640D01*
X130348Y-522535D01*
X130975Y-522640D01*
X131523Y-523060D01*
X131993Y-523690D01*
X132306Y-524425D01*
X132463Y-525265D01*
Y-526105D01*
X132306Y-526945D01*
X131993Y-527680D01*
X131523Y-528310D01*
X130975Y-528730D01*
X130348Y-528835D01*
G01X136648Y-529045D02*
X136491Y-528940D01*
Y-528730D01*
X136648Y-528625D01*
X136805Y-528730D01*
Y-528940D01*
X136648Y-529045D01*
G01X144671Y-523060D02*
X144201Y-522745D01*
X143653Y-522535D01*
X143026D01*
X142321Y-522850D01*
X141773Y-523375D01*
X141381Y-524005D01*
X141068Y-525055D01*
X140990Y-526000D01*
X141146Y-526945D01*
X141381Y-527575D01*
X141851Y-528205D01*
X142400Y-528625D01*
X142948Y-528835D01*
X143496D01*
X144045Y-528625D01*
X144515Y-528310D01*
X144906Y-527890D01*
G01X149248Y-529045D02*
X149091Y-528940D01*
Y-528730D01*
X149248Y-528625D01*
X149405Y-528730D01*
Y-528940D01*
X149248Y-529045D01*
G01X155940Y-530935D02*
X156723Y-529885D01*
X157115Y-528835D01*
Y-524635D01*
X156723Y-523585D01*
X155940Y-522535D01*
G01X-10054Y-508835D02*
Y-502535D01*
X-6450Y-508835D01*
Y-502535D01*
G01X-1952Y-508835D02*
X-2579Y-508730D01*
X-3127Y-508310D01*
X-3597Y-507680D01*
X-3910Y-506945D01*
X-4067Y-506105D01*
Y-505265D01*
X-3910Y-504425D01*
X-3597Y-503690D01*
X-3127Y-503060D01*
X-2579Y-502640D01*
X-1952Y-502535D01*
X-1325Y-502640D01*
X-777Y-503060D01*
X-307Y-503690D01*
X6Y-504425D01*
X163Y-505265D01*
Y-506105D01*
X6Y-506945D01*
X-307Y-507680D01*
X-777Y-508310D01*
X-1325Y-508730D01*
X-1952Y-508835D01*
G01X4348Y-509045D02*
X4191Y-508940D01*
Y-508730D01*
X4348Y-508625D01*
X4505Y-508730D01*
Y-508940D01*
X4348Y-509045D01*
G01X9160Y-503585D02*
X9630Y-502955D01*
X10178Y-502640D01*
X10805Y-502535D01*
X11588Y-502745D01*
X12136Y-503270D01*
X12293Y-503900D01*
X12215Y-504530D01*
X11901Y-505055D01*
X10335Y-506105D01*
X9630Y-506840D01*
X9160Y-507890D01*
X9003Y-508835D01*
X12293D01*
G01X16948D02*
Y-502535D01*
X16008Y-503795D01*
G01Y-508835D02*
X17888D01*
G01X23248D02*
Y-502535D01*
X22308Y-503795D01*
G01Y-508835D02*
X24188D01*
G01X29391Y-509990D02*
X29705Y-508625D01*
G01X33498Y-502535D02*
X34595Y-508835D01*
X35848Y-502535D01*
X37101Y-508835D01*
X38198Y-502535D01*
G01X43715Y-508835D02*
X40581D01*
Y-502535D01*
X43715D01*
G01X42461Y-505580D02*
X40581D01*
G01X46646Y-508835D02*
Y-502535D01*
X50250Y-508835D01*
Y-502535D01*
G01X53103Y-508835D02*
Y-502535D01*
G01X56393D02*
Y-508835D01*
G01Y-505685D02*
X53103D01*
G01X59325Y-502535D02*
Y-507050D01*
X59638Y-507995D01*
X60265Y-508625D01*
X61048Y-508835D01*
X61831Y-508625D01*
X62458Y-507995D01*
X62771Y-507050D01*
Y-502535D01*
G01X65390Y-508835D02*
X67348Y-502535D01*
X69306Y-508835D01*
G01X68601Y-506630D02*
X66095D01*
G01X78460Y-503585D02*
X78930Y-502955D01*
X79478Y-502640D01*
X80105Y-502535D01*
X80888Y-502745D01*
X81436Y-503270D01*
X81593Y-503900D01*
X81515Y-504530D01*
X81201Y-505055D01*
X79635Y-506105D01*
X78930Y-506840D01*
X78460Y-507890D01*
X78303Y-508835D01*
X81593D01*
G01X84446D02*
Y-502535D01*
X88050Y-508835D01*
Y-502535D01*
G01X90825Y-508835D02*
Y-502535D01*
X92391D01*
X93018Y-502850D01*
X93488Y-503270D01*
X93880Y-503900D01*
X94193Y-504635D01*
X94271Y-505685D01*
X94193Y-506735D01*
X93880Y-507470D01*
X93488Y-508100D01*
X93018Y-508520D01*
X92391Y-508835D01*
X90825D01*
G01X103581D02*
Y-502535D01*
X105540D01*
X106166Y-502850D01*
X106558Y-503270D01*
X106715Y-504110D01*
X106558Y-504950D01*
X106088Y-505475D01*
X105540Y-505790D01*
X103581D01*
G01X105540D02*
X106715Y-508835D01*
G01X109725D02*
Y-502535D01*
X111291D01*
X111918Y-502850D01*
X112388Y-503270D01*
X112780Y-503900D01*
X113093Y-504635D01*
X113171Y-505685D01*
X113093Y-506735D01*
X112780Y-507470D01*
X112388Y-508100D01*
X111918Y-508520D01*
X111291Y-508835D01*
X109725D01*
G01X117748Y-509045D02*
X117591Y-508940D01*
Y-508730D01*
X117748Y-508625D01*
X117905Y-508730D01*
Y-508940D01*
X117748Y-509045D01*
G01X14048Y-498135D02*
X11528Y-497718D01*
X9323Y-496052D01*
X7433Y-493552D01*
X6173Y-490635D01*
X5543Y-487302D01*
Y-483968D01*
X6173Y-480635D01*
X7433Y-477718D01*
X9323Y-475219D01*
X11528Y-473552D01*
X14048Y-473135D01*
X16568Y-473552D01*
X18773Y-475219D01*
X20663Y-477718D01*
X21923Y-480635D01*
X22553Y-483968D01*
Y-487302D01*
X21923Y-490635D01*
X20663Y-493552D01*
X18773Y-496052D01*
X16568Y-497718D01*
X14048Y-498135D01*
G01X16568Y-491468D02*
X20348Y-498135D01*
G01X33893Y-481469D02*
Y-493135D01*
X35153Y-496052D01*
X37043Y-497718D01*
X39248Y-498135D01*
X41453Y-497718D01*
X43343Y-496052D01*
X44603Y-493135D01*
G01Y-498135D02*
Y-481469D01*
G01X70118Y-498135D02*
Y-481469D01*
G01Y-484385D02*
X68858Y-482719D01*
X66968Y-481885D01*
X64763Y-481469D01*
X62558Y-482302D01*
X60668Y-483968D01*
X59408Y-486469D01*
X58778Y-489802D01*
X59408Y-493135D01*
X60668Y-495636D01*
X62558Y-497302D01*
X64763Y-498135D01*
X66968Y-497718D01*
X68858Y-496469D01*
X70118Y-494802D01*
G01X84293Y-498135D02*
Y-481469D01*
G01Y-485635D02*
X85553Y-483552D01*
X87443Y-481885D01*
X89963Y-481469D01*
X92168Y-481885D01*
X94058Y-483552D01*
X95003Y-486469D01*
Y-498135D01*
G01X114848Y-473135D02*
Y-498135D01*
G01X110438Y-481469D02*
X119258D01*
G01X145718Y-498135D02*
Y-481469D01*
G01Y-484385D02*
X144458Y-482719D01*
X142568Y-481885D01*
X140363Y-481469D01*
X138158Y-482302D01*
X136268Y-483968D01*
X135008Y-486469D01*
X134378Y-489802D01*
X135008Y-493135D01*
X136268Y-495636D01*
X138158Y-497302D01*
X140363Y-498135D01*
X142568Y-497718D01*
X144458Y-496469D01*
X145718Y-494802D01*
G01X196898Y-510835D02*
Y-502835D01*
X199298D01*
X200098Y-503235D01*
X200698Y-504168D01*
X200898Y-505235D01*
X200698Y-506302D01*
X200198Y-507102D01*
X199298Y-507502D01*
X196898D01*
G01X204398Y-510835D02*
X206898Y-502835D01*
X209398Y-510835D01*
G01X208498Y-508035D02*
X205298D01*
G01X212798Y-509769D02*
X213598Y-510435D01*
X214498Y-510835D01*
X215298D01*
X216098Y-510435D01*
X216698Y-509769D01*
X216998Y-508835D01*
X216798Y-507902D01*
X216298Y-507102D01*
X215398Y-506568D01*
X214198Y-506302D01*
X213498Y-505768D01*
X213198Y-504835D01*
X213398Y-503902D01*
X213898Y-503235D01*
X214598Y-502835D01*
X215298D01*
X215998Y-503102D01*
X216598Y-503768D01*
G01X222898Y-502835D02*
Y-510835D01*
G01X220598Y-502835D02*
X225198D01*
G01X229598Y-508168D02*
X232198D01*
G01X239698Y-506568D02*
X240098Y-506168D01*
X240398Y-505502D01*
X240598Y-504568D01*
X240398Y-503768D01*
X239998Y-503235D01*
X239298Y-502835D01*
X236598D01*
Y-510835D01*
X239898D01*
X240598Y-510302D01*
X240998Y-509502D01*
X241198Y-508568D01*
X240998Y-507635D01*
X240398Y-506835D01*
X239698Y-506568D01*
X236598D01*
G01X246898Y-510835D02*
X246098Y-510702D01*
X245398Y-510168D01*
X244798Y-509368D01*
X244398Y-508435D01*
X244198Y-507368D01*
Y-506302D01*
X244398Y-505235D01*
X244798Y-504302D01*
X245398Y-503502D01*
X246098Y-502968D01*
X246898Y-502835D01*
X247698Y-502968D01*
X248398Y-503502D01*
X248998Y-504302D01*
X249398Y-505235D01*
X249598Y-506302D01*
Y-507368D01*
X249398Y-508435D01*
X248998Y-509368D01*
X248398Y-510168D01*
X247698Y-510702D01*
X246898Y-510835D01*
G01X254898Y-502835D02*
Y-510835D01*
G01X252598Y-502835D02*
X257198D01*
G01X185398Y-477835D02*
Y-485835D01*
X189398D01*
G01X197198D02*
Y-480502D01*
G01Y-481435D02*
X196798Y-480902D01*
X196198Y-480635D01*
X195498Y-480502D01*
X194798Y-480768D01*
X194198Y-481302D01*
X193798Y-482102D01*
X193598Y-483168D01*
X193798Y-484235D01*
X194198Y-485035D01*
X194798Y-485568D01*
X195498Y-485835D01*
X196198Y-485702D01*
X196798Y-485302D01*
X197198Y-484769D01*
G01X201298Y-488235D02*
X201898Y-488502D01*
X202698Y-488235D01*
X203198Y-487702D01*
X203598Y-487035D01*
X204198Y-484902D01*
X205498Y-480502D01*
G01X202298D02*
X204198Y-484902D01*
G01X209898Y-482235D02*
X213098D01*
X212798Y-481302D01*
X212298Y-480768D01*
X211598Y-480502D01*
X210898Y-480635D01*
X210298Y-481035D01*
X209898Y-481968D01*
X209698Y-482769D01*
Y-483568D01*
X209898Y-484368D01*
X210398Y-485168D01*
X210998Y-485702D01*
X211698Y-485835D01*
X212398Y-485568D01*
X213098Y-484769D01*
G01X217998Y-485835D02*
Y-480502D01*
G01Y-481568D02*
X218498Y-481035D01*
X218998Y-480635D01*
X219698Y-480502D01*
X220198Y-480635D01*
X220798Y-481035D01*
G01X211398Y-535835D02*
Y-532235D01*
X209398Y-527835D01*
G01X213398D02*
X211398Y-532235D01*
G01X217698Y-530502D02*
Y-534235D01*
X218098Y-535168D01*
X218698Y-535702D01*
X219398Y-535835D01*
X220098Y-535702D01*
X220698Y-535168D01*
X221098Y-534235D01*
G01Y-535835D02*
Y-530502D01*
G01X225698Y-535835D02*
Y-530502D01*
G01Y-531835D02*
X226098Y-531168D01*
X226698Y-530635D01*
X227498Y-530502D01*
X228198Y-530635D01*
X228798Y-531168D01*
X229098Y-532102D01*
Y-535835D01*
G01X237198D02*
Y-530502D01*
G01Y-531435D02*
X236798Y-530902D01*
X236198Y-530635D01*
X235498Y-530502D01*
X234798Y-530768D01*
X234198Y-531302D01*
X233798Y-532102D01*
X233598Y-533168D01*
X233798Y-534235D01*
X234198Y-535035D01*
X234798Y-535568D01*
X235498Y-535835D01*
X236198Y-535702D01*
X236798Y-535302D01*
X237198Y-534769D01*
G01X311998Y-529168D02*
X312598Y-528368D01*
X313298Y-527968D01*
X314098Y-527835D01*
X315098Y-528102D01*
X315798Y-528768D01*
X315998Y-529568D01*
X315898Y-530369D01*
X315498Y-531035D01*
X313498Y-532368D01*
X312598Y-533302D01*
X311998Y-534635D01*
X311798Y-535835D01*
X315998D01*
G01X321898Y-527835D02*
X321098Y-528102D01*
X320498Y-528768D01*
X320098Y-529568D01*
X319798Y-530635D01*
X319698Y-531835D01*
X319798Y-533035D01*
X320098Y-534102D01*
X320498Y-534902D01*
X321098Y-535568D01*
X321898Y-535835D01*
X322698Y-535568D01*
X323298Y-534902D01*
X323698Y-534102D01*
X323998Y-533035D01*
X324098Y-531835D01*
X323998Y-530635D01*
X323698Y-529568D01*
X323298Y-528768D01*
X322698Y-528102D01*
X321898Y-527835D01*
G01X327998Y-529168D02*
X328598Y-528368D01*
X329298Y-527968D01*
X330098Y-527835D01*
X331098Y-528102D01*
X331798Y-528768D01*
X331998Y-529568D01*
X331898Y-530369D01*
X331498Y-531035D01*
X329498Y-532368D01*
X328598Y-533302D01*
X327998Y-534635D01*
X327798Y-535835D01*
X331998D01*
G01X335698Y-534235D02*
X336298Y-535168D01*
X337098Y-535702D01*
X337998Y-535835D01*
X338798Y-535702D01*
X339598Y-535035D01*
X340098Y-534235D01*
X340198Y-533435D01*
X339998Y-532502D01*
X339298Y-531835D01*
X338598Y-531568D01*
X337698D01*
G01X338598D02*
X339198Y-531168D01*
X339698Y-530502D01*
X339898Y-529702D01*
X339698Y-528902D01*
X339198Y-528235D01*
X338298Y-527835D01*
X337398Y-527968D01*
X336498Y-528502D01*
G01X344098Y-536102D02*
X347698Y-527835D01*
G01X353898D02*
X353098Y-528102D01*
X352498Y-528768D01*
X352098Y-529568D01*
X351798Y-530635D01*
X351698Y-531835D01*
X351798Y-533035D01*
X352098Y-534102D01*
X352498Y-534902D01*
X353098Y-535568D01*
X353898Y-535835D01*
X354698Y-535568D01*
X355298Y-534902D01*
X355698Y-534102D01*
X355998Y-533035D01*
X356098Y-531835D01*
X355998Y-530635D01*
X355698Y-529568D01*
X355298Y-528768D01*
X354698Y-528102D01*
X353898Y-527835D01*
G01X361898Y-535835D02*
Y-527835D01*
X360698Y-529435D01*
G01Y-535835D02*
X363098D01*
G01X368098Y-536102D02*
X371698Y-527835D01*
G01X377898D02*
X377098Y-528102D01*
X376498Y-528768D01*
X376098Y-529568D01*
X375798Y-530635D01*
X375698Y-531835D01*
X375798Y-533035D01*
X376098Y-534102D01*
X376498Y-534902D01*
X377098Y-535568D01*
X377898Y-535835D01*
X378698Y-535568D01*
X379298Y-534902D01*
X379698Y-534102D01*
X379998Y-533035D01*
X380098Y-531835D01*
X379998Y-530635D01*
X379698Y-529568D01*
X379298Y-528768D01*
X378698Y-528102D01*
X377898Y-527835D01*
G01X384198Y-534902D02*
X384898Y-535568D01*
X385698Y-535835D01*
X386498Y-535568D01*
X387198Y-534769D01*
X387698Y-533568D01*
X387898Y-532368D01*
Y-530902D01*
X387698Y-529702D01*
X387198Y-528635D01*
X386598Y-528102D01*
X385898Y-527835D01*
X385098Y-528102D01*
X384498Y-528635D01*
X384098Y-529435D01*
X383898Y-530502D01*
X384098Y-531435D01*
X384598Y-532368D01*
X385198Y-532902D01*
X385898Y-533035D01*
X386698Y-532769D01*
X387298Y-532102D01*
X387898Y-530902D01*
G01X311698Y-510835D02*
Y-502835D01*
X313698D01*
X314498Y-503235D01*
X315098Y-503768D01*
X315598Y-504568D01*
X315998Y-505502D01*
X316098Y-506835D01*
X315998Y-508168D01*
X315598Y-509102D01*
X315098Y-509902D01*
X314498Y-510435D01*
X313698Y-510835D01*
X311698D01*
G01X319398D02*
X321898Y-502835D01*
X324398Y-510835D01*
G01X323498Y-508035D02*
X320298D01*
G01X329898Y-502835D02*
X329098Y-503102D01*
X328498Y-503768D01*
X328098Y-504568D01*
X327798Y-505635D01*
X327698Y-506835D01*
X327798Y-508035D01*
X328098Y-509102D01*
X328498Y-509902D01*
X329098Y-510568D01*
X329898Y-510835D01*
X330698Y-510568D01*
X331298Y-509902D01*
X331698Y-509102D01*
X331998Y-508035D01*
X332098Y-506835D01*
X331998Y-505635D01*
X331698Y-504568D01*
X331298Y-503768D01*
X330698Y-503102D01*
X329898Y-502835D01*
G01X335998Y-510835D02*
Y-502835D01*
X339798D01*
G01X338398Y-506702D02*
X335998D01*
G01X345898Y-502835D02*
X345098Y-503102D01*
X344498Y-503768D01*
X344098Y-504568D01*
X343798Y-505635D01*
X343698Y-506835D01*
X343798Y-508035D01*
X344098Y-509102D01*
X344498Y-509902D01*
X345098Y-510568D01*
X345898Y-510835D01*
X346698Y-510568D01*
X347298Y-509902D01*
X347698Y-509102D01*
X347998Y-508035D01*
X348098Y-506835D01*
X347998Y-505635D01*
X347698Y-504568D01*
X347298Y-503768D01*
X346698Y-503102D01*
X345898Y-502835D01*
G01X353898D02*
Y-510835D01*
G01X351598Y-502835D02*
X356198D01*
G01X363898Y-510835D02*
X359898D01*
Y-502835D01*
X363898D01*
G01X362298Y-506702D02*
X359898D01*
G01X370698Y-506568D02*
X371098Y-506168D01*
X371398Y-505502D01*
X371598Y-504568D01*
X371398Y-503768D01*
X370998Y-503235D01*
X370298Y-502835D01*
X367598D01*
Y-510835D01*
X370898D01*
X371598Y-510302D01*
X371998Y-509502D01*
X372198Y-508568D01*
X371998Y-507635D01*
X371398Y-506835D01*
X370698Y-506568D01*
X367598D01*
G01X376698Y-502835D02*
X379098D01*
G01X377898D02*
Y-510835D01*
G01X376698D02*
X379098D01*
G01X383998D02*
Y-502835D01*
X387798D01*
G01X386398Y-506702D02*
X383998D01*
G01X393898Y-502835D02*
X393098Y-503102D01*
X392498Y-503768D01*
X392098Y-504568D01*
X391798Y-505635D01*
X391698Y-506835D01*
X391798Y-508035D01*
X392098Y-509102D01*
X392498Y-509902D01*
X393098Y-510568D01*
X393898Y-510835D01*
X394698Y-510568D01*
X395298Y-509902D01*
X395698Y-509102D01*
X395998Y-508035D01*
X396098Y-506835D01*
X395998Y-505635D01*
X395698Y-504568D01*
X395298Y-503768D01*
X394698Y-503102D01*
X393898Y-502835D01*
G01X329498Y-485835D02*
Y-477835D01*
X333298D01*
G01X331898Y-481702D02*
X329498D01*
G01X339398Y-477835D02*
X338598Y-478102D01*
X337998Y-478768D01*
X337598Y-479568D01*
X337298Y-480635D01*
X337198Y-481835D01*
X337298Y-483035D01*
X337598Y-484102D01*
X337998Y-484902D01*
X338598Y-485568D01*
X339398Y-485835D01*
X340198Y-485568D01*
X340798Y-484902D01*
X341198Y-484102D01*
X341498Y-483035D01*
X341598Y-481835D01*
X341498Y-480635D01*
X341198Y-479568D01*
X340798Y-478768D01*
X340198Y-478102D01*
X339398Y-477835D01*
G01X347398D02*
Y-485835D01*
G01X345098Y-477835D02*
X349698D01*
G01X352398Y-488502D02*
X358398D01*
G01X361898Y-482235D02*
X365098D01*
X364798Y-481302D01*
X364298Y-480768D01*
X363598Y-480502D01*
X362898Y-480635D01*
X362298Y-481035D01*
X361898Y-481968D01*
X361698Y-482769D01*
Y-483568D01*
X361898Y-484368D01*
X362398Y-485168D01*
X362998Y-485702D01*
X363698Y-485835D01*
X364398Y-485568D01*
X365098Y-484769D01*
G01X369898Y-480502D02*
X372898Y-485835D01*
G01Y-480502D02*
X369898Y-485835D01*
G01X377598Y-488502D02*
Y-480502D01*
G01Y-481702D02*
X378098Y-481035D01*
X378598Y-480635D01*
X379398Y-480502D01*
X380098Y-480635D01*
X380798Y-481302D01*
X381098Y-482235D01*
X381198Y-483168D01*
X381098Y-484102D01*
X380798Y-485035D01*
X380198Y-485568D01*
X379398Y-485835D01*
X378698Y-485702D01*
X377998Y-485302D01*
X377598Y-484769D01*
G01X389198Y-485835D02*
Y-480502D01*
G01Y-481435D02*
X388798Y-480902D01*
X388198Y-480635D01*
X387498Y-480502D01*
X386798Y-480768D01*
X386198Y-481302D01*
X385798Y-482102D01*
X385598Y-483168D01*
X385798Y-484235D01*
X386198Y-485035D01*
X386798Y-485568D01*
X387498Y-485835D01*
X388198Y-485702D01*
X388798Y-485302D01*
X389198Y-484769D01*
G01X393698Y-485835D02*
Y-480502D01*
G01Y-481835D02*
X394098Y-481168D01*
X394698Y-480635D01*
X395498Y-480502D01*
X396198Y-480635D01*
X396798Y-481168D01*
X397098Y-482102D01*
Y-485835D01*
G01X405198Y-477835D02*
Y-485835D01*
G01Y-484635D02*
X404798Y-485302D01*
X404198Y-485702D01*
X403498Y-485835D01*
X402698Y-485568D01*
X402098Y-484902D01*
X401698Y-484102D01*
X401598Y-483168D01*
X401698Y-482235D01*
X402098Y-481435D01*
X402698Y-480768D01*
X403498Y-480502D01*
X404198Y-480635D01*
X404698Y-480902D01*
X405198Y-481435D01*
G01X409898Y-482235D02*
X413098D01*
X412798Y-481302D01*
X412298Y-480768D01*
X411598Y-480502D01*
X410898Y-480635D01*
X410298Y-481035D01*
X409898Y-481968D01*
X409698Y-482769D01*
Y-483568D01*
X409898Y-484368D01*
X410398Y-485168D01*
X410998Y-485702D01*
X411698Y-485835D01*
X412398Y-485568D01*
X413098Y-484769D01*
G01X417998Y-485835D02*
Y-480502D01*
G01Y-481568D02*
X418498Y-481035D01*
X418998Y-480635D01*
X419698Y-480502D01*
X420198Y-480635D01*
X420798Y-481035D01*
G01X424398Y-488502D02*
X430398D01*
G01X433598Y-485835D02*
Y-477835D01*
G01Y-481835D02*
X434098Y-481035D01*
X434698Y-480635D01*
X435298Y-480502D01*
X436198Y-480768D01*
X436798Y-481302D01*
X437198Y-482235D01*
Y-483302D01*
X436998Y-484368D01*
X436598Y-485168D01*
X435898Y-485702D01*
X435298Y-485835D01*
X434698Y-485702D01*
X434098Y-485302D01*
X433598Y-484635D01*
G01X445198Y-477835D02*
Y-485835D01*
G01Y-484635D02*
X444798Y-485302D01*
X444198Y-485702D01*
X443498Y-485835D01*
X442698Y-485568D01*
X442098Y-484902D01*
X441698Y-484102D01*
X441598Y-483168D01*
X441698Y-482235D01*
X442098Y-481435D01*
X442698Y-480768D01*
X443498Y-480502D01*
X444198Y-480635D01*
X444698Y-480902D01*
X445198Y-481435D01*
G01X400398Y-538835D02*
Y-530835D01*
X399198Y-532435D01*
G01Y-538835D02*
X401598D01*
G01X406498Y-535502D02*
X407198Y-534568D01*
X407798Y-534035D01*
X408598Y-533768D01*
X409298Y-534035D01*
X409798Y-534568D01*
X410198Y-535368D01*
X410298Y-536302D01*
X410198Y-537102D01*
X409798Y-537902D01*
X409198Y-538568D01*
X408498Y-538835D01*
X407698Y-538568D01*
X406998Y-537769D01*
X406598Y-536568D01*
X406498Y-535235D01*
X406698Y-533502D01*
X406998Y-532568D01*
X407498Y-531635D01*
X408198Y-530968D01*
X408898Y-530835D01*
X409598Y-531102D01*
X410098Y-531768D01*
G01X416398Y-539102D02*
X416198Y-538968D01*
Y-538702D01*
X416398Y-538568D01*
X416598Y-538702D01*
Y-538968D01*
X416398Y-539102D01*
G01X422498Y-535502D02*
X423198Y-534568D01*
X423798Y-534035D01*
X424598Y-533768D01*
X425298Y-534035D01*
X425798Y-534568D01*
X426198Y-535368D01*
X426298Y-536302D01*
X426198Y-537102D01*
X425798Y-537902D01*
X425198Y-538568D01*
X424498Y-538835D01*
X423698Y-538568D01*
X422998Y-537769D01*
X422598Y-536568D01*
X422498Y-535235D01*
X422698Y-533502D01*
X422998Y-532568D01*
X423498Y-531635D01*
X424198Y-530968D01*
X424898Y-530835D01*
X425598Y-531102D01*
X426098Y-531768D01*
G01X445398Y-538835D02*
Y-530835D01*
X444198Y-532435D01*
G01Y-538835D02*
X446598D01*
G01X453198D02*
X453398Y-537102D01*
X453698Y-535635D01*
X454098Y-534302D01*
X454598Y-532835D01*
X455398Y-530835D01*
X451398D01*
G01X461398Y-539102D02*
X461198Y-538968D01*
Y-538702D01*
X461398Y-538568D01*
X461598Y-538702D01*
Y-538968D01*
X461398Y-539102D01*
G01X467498Y-532168D02*
X468098Y-531368D01*
X468798Y-530968D01*
X469598Y-530835D01*
X470598Y-531102D01*
X471298Y-531768D01*
X471498Y-532568D01*
X471398Y-533369D01*
X470998Y-534035D01*
X468998Y-535368D01*
X468098Y-536302D01*
X467498Y-537635D01*
X467298Y-538835D01*
X471498D01*
G01X465498Y-513835D02*
Y-505835D01*
X469298D01*
G01X467898Y-509702D02*
X465498D01*
G54D68*
X1030635Y824546D03*
G54D59*
X876402Y797415D03*
X890326Y828548D03*
X895050D03*
X898835Y831912D03*
X893843Y832448D03*
X886120Y832295D03*
X955712Y833988D03*
X978978Y817618D03*
X984357Y777555D03*
X997051Y778833D03*
X990699Y778630D03*
X987990Y774005D03*
X987394Y787490D03*
X994051Y810871D03*
X996385Y816141D03*
X1007990Y765899D03*
X999990Y764566D03*
X1012695Y776728D03*
X999990Y774671D03*
X1011156Y809889D03*
X998376Y805985D03*
X1006054Y810969D03*
X1010699Y803454D03*
X1018015Y751565D03*
X1017664Y779101D03*
X1018071Y798490D03*
X1017955Y812097D03*
X1274396Y866896D03*
X1324470Y908192D03*
G54D69*
X1131743Y779174D03*
X1139617Y775434D03*
Y782914D03*
M02*
